FILE_TYPE = MACRO_DRAWING;
SET COLOR_WIRE YELLOW;
SET COLOR_PROP ORANGE;
SET COLOR_DOT WHITE;
SET COLOR_ARC YELLOW;
SET COLOR_BODY GREEN;
SET COLOR_NOTE PURPLE;
SET PROP_DISPLAY VALUE;
SET PAGE_NUMBER P110;
FORCEADD 9ZXL0451EKILFT..1
(7725 1875);
FORCEPROP 1 LAST LOCATION U69
J 0
(7259 2890);
DISPLAY 0.489362 (7259 2890);
PAINT SKYBLUE (7259 2890);
FORCEPROP 0 LAST $SEC 1
J 0
(7350 3300);
DISPLAY 0.680851 (7350 3300);
PAINT MONO (7350 3300);
DISPLAY INVISIBLE (7350 3300);
FORCEPROP 0 LAST CDS_SEC 1
J 0
(7350 3300);
DISPLAY 0.680851 (7350 3300);
DISPLAY INVISIBLE (7350 3300);
FORCEPROP 0 LASTPIN (7100 1650) $PN 1
J 2
(7090 1660);
DISPLAY 0.489362 (7090 1660);
PAINT MONO (7090 1660);
FORCEPROP 0 LASTPIN (8350 2350) $PN 32
J 0
(8360 2360);
DISPLAY 0.489362 (8360 2360);
PAINT MONO (8360 2360);
FORCEPROP 0 LASTPIN (8350 2150) $PN 13
J 0
(8360 2160);
DISPLAY 0.489362 (8360 2160);
PAINT MONO (8360 2160);
FORCEPROP 0 LASTPIN (8350 2100) $PN 14
J 0
(8360 2110);
DISPLAY 0.489362 (8360 2110);
PAINT MONO (8360 2110);
FORCEPROP 0 LASTPIN (8350 2050) $PN 19
J 0
(8360 2060);
DISPLAY 0.489362 (8360 2060);
PAINT MONO (8360 2060);
FORCEPROP 0 LASTPIN (8350 2000) $PN 20
J 0
(8360 2010);
DISPLAY 0.489362 (8360 2010);
PAINT MONO (8360 2010);
FORCEPROP 0 LASTPIN (8350 1950) $PN 22
J 0
(8360 1960);
DISPLAY 0.489362 (8360 1960);
PAINT MONO (8360 1960);
FORCEPROP 0 LASTPIN (8350 1900) $PN 23
J 0
(8360 1910);
DISPLAY 0.489362 (8360 1910);
PAINT MONO (8360 1910);
FORCEPROP 0 LASTPIN (8350 1850) $PN 27
J 0
(8360 1860);
DISPLAY 0.489362 (8360 1860);
PAINT MONO (8360 1860);
FORCEPROP 0 LASTPIN (8350 1800) $PN 28
J 0
(8360 1810);
DISPLAY 0.489362 (8360 1810);
PAINT MONO (8360 1810);
FORCEPROP 0 LASTPIN (7100 2050) $PN 3
J 2
(7090 2060);
DISPLAY 0.489362 (7090 2060);
PAINT MONO (7090 2060);
FORCEPROP 0 LASTPIN (7100 2000) $PN 4
J 2
(7090 2010);
DISPLAY 0.489362 (7090 2010);
PAINT MONO (7090 2010);
FORCEPROP 0 LASTPIN (8350 1250) $PN 33
J 0
(8360 1260);
DISPLAY 0.489362 (8360 1260);
PAINT MONO (8360 1260);
FORCEPROP 0 LASTPIN (7100 1600) $PN 9
J 2
(7090 1610);
DISPLAY 0.489362 (7090 1610);
PAINT MONO (7090 1610);
FORCEPROP 0 LASTPIN (7100 1550) $PN 8
J 2
(7090 1560);
DISPLAY 0.489362 (7090 1560);
PAINT MONO (7090 1560);
FORCEPROP 0 LASTPIN (7100 1400) $PN 10
J 2
(7090 1410);
DISPLAY 0.489362 (7090 1410);
PAINT MONO (7090 1410);
FORCEPROP 0 LASTPIN (7100 1350) $PN 11
J 2
(7090 1360);
DISPLAY 0.489362 (7090 1360);
PAINT MONO (7090 1360);
FORCEPROP 0 LASTPIN (7100 1300) $PN 17
J 2
(7090 1310);
DISPLAY 0.489362 (7090 1310);
PAINT MONO (7090 1310);
FORCEPROP 0 LASTPIN (7100 1250) $PN 30
J 2
(7090 1260);
DISPLAY 0.489362 (7090 1260);
PAINT MONO (7090 1260);
FORCEPROP 0 LASTPIN (7100 1750) $PN 7
J 2
(7090 1760);
DISPLAY 0.489362 (7090 1760);
PAINT MONO (7090 1760);
FORCEPROP 0 LASTPIN (7100 1800) $PN 6
J 2
(7090 1810);
DISPLAY 0.489362 (7090 1810);
PAINT MONO (7090 1810);
FORCEPROP 0 LASTPIN (7100 2500) $PN 12
J 2
(7090 2510);
DISPLAY 0.489362 (7090 2510);
PAINT MONO (7090 2510);
FORCEPROP 0 LASTPIN (7100 2450) $PN 16
J 2
(7090 2460);
DISPLAY 0.489362 (7090 2460);
PAINT MONO (7090 2460);
FORCEPROP 0 LASTPIN (7100 2400) $PN 21
J 2
(7090 2410);
DISPLAY 0.489362 (7090 2410);
PAINT MONO (7090 2410);
FORCEPROP 0 LASTPIN (7100 2350) $PN 25
J 2
(7090 2360);
DISPLAY 0.489362 (7090 2360);
PAINT MONO (7090 2360);
FORCEPROP 0 LASTPIN (7100 2300) $PN 29
J 2
(7090 2310);
DISPLAY 0.489362 (7090 2310);
PAINT MONO (7090 2310);
FORCEPROP 0 LASTPIN (8350 2500) $PN 31
J 0
(8360 2510);
DISPLAY 0.489362 (8360 2510);
PAINT MONO (8360 2510);
FORCEPROP 0 LASTPIN (7100 2200) $PN 2
J 2
(7090 2210);
DISPLAY 0.489362 (7090 2210);
PAINT MONO (7090 2210);
FORCEPROP 0 LASTPIN (8350 1600) $PN 15
J 0
(8360 1610);
DISPLAY 0.489362 (8360 1610);
PAINT MONO (8360 1610);
FORCEPROP 0 LASTPIN (8350 1550) $PN 18
J 0
(8360 1560);
DISPLAY 0.489362 (8360 1560);
PAINT MONO (8360 1560);
FORCEPROP 0 LASTPIN (8350 1500) $PN 24
J 0
(8360 1510);
DISPLAY 0.489362 (8360 1510);
PAINT MONO (8360 1510);
FORCEPROP 0 LASTPIN (8350 1450) $PN 26
J 0
(8360 1460);
DISPLAY 0.489362 (8360 1460);
PAINT MONO (8360 1460);
FORCEPROP 0 LASTPIN (7100 1900) $PN 5
J 2
(7090 1910);
DISPLAY 0.489362 (7090 1910);
PAINT MONO (7090 1910);
FORCEPROP 2 LAST PART_TYPE SMLF
J 0
(7350 3250);
DISPLAY 0.680851 (7350 3250);
FORCEPROP 1 LAST MATERIAL IC
J 0
(7259 2616);
DISPLAY 0.489362 (7259 2616);
PAINT SKYBLUE (7259 2616);
FORCEPROP 2 LAST VALUE 9ZXL0451EKILFT
J 0
(7350 3200);
DISPLAY 0.489362 (7350 3200);
PAINT SKYBLUE (7350 3200);
FORCEPROP 1 LAST PART_NUMBER AL000451003
J 0
(7259 2743);
DISPLAY 0.489362 (7259 2743);
PAINT SKYBLUE (7259 2743);
FORCEPROP 1 LAST NEEDS_NO_SIZE TRUE
J 0
(7725 1875);
DISPLAY 0.723404 (7725 1875);
PAINT GREEN (7725 1875);
DISPLAY INVISIBLE (7725 1875);
FORCEPROP 1 LAST CDS_LMAN_SYM_OUTLINE -475,725,475,-725
J 0
(7725 1875);
DISPLAY 0.468085 (7725 1875);
PAINT GREEN (7725 1875);
DISPLAY INVISIBLE (7725 1875);
FORCEPROP 2 LAST CDS_LIB pure_quanta
J 0
(7725 1875);
DISPLAY INVISIBLE (7725 1875);
FORCEPROP 1 LAST PATH I225
J 0
(7725 1875);
DISPLAY 0.723404 (7725 1875);
PAINT GREEN (7725 1875);
DISPLAY INVISIBLE (7725 1875);
FORCEADD 9ZXL0451EKILFT..1
(7700 5050);
FORCEPROP 1 LAST LOCATION U68
J 0
(7234 6065);
DISPLAY 0.489362 (7234 6065);
PAINT SKYBLUE (7234 6065);
FORCEPROP 0 LAST $SEC 1
J 0
(7300 6475);
DISPLAY 0.680851 (7300 6475);
PAINT MONO (7300 6475);
DISPLAY INVISIBLE (7300 6475);
FORCEPROP 0 LAST CDS_SEC 1
J 0
(7325 6475);
DISPLAY 1.021277 (7325 6475);
DISPLAY INVISIBLE (7325 6475);
FORCEPROP 0 LASTPIN (7075 4825) $PN 1
J 2
(7065 4835);
DISPLAY 0.489362 (7065 4835);
PAINT MONO (7065 4835);
FORCEPROP 0 LASTPIN (8325 5525) $PN 32
J 0
(8335 5535);
DISPLAY 0.489362 (8335 5535);
PAINT MONO (8335 5535);
FORCEPROP 0 LASTPIN (8325 5325) $PN 13
J 0
(8335 5335);
DISPLAY 0.489362 (8335 5335);
PAINT MONO (8335 5335);
FORCEPROP 0 LASTPIN (8325 5275) $PN 14
J 0
(8335 5285);
DISPLAY 0.489362 (8335 5285);
PAINT MONO (8335 5285);
FORCEPROP 0 LASTPIN (8325 5225) $PN 19
J 0
(8335 5235);
DISPLAY 0.489362 (8335 5235);
PAINT MONO (8335 5235);
FORCEPROP 0 LASTPIN (8325 5175) $PN 20
J 0
(8335 5185);
DISPLAY 0.489362 (8335 5185);
PAINT MONO (8335 5185);
FORCEPROP 0 LASTPIN (8325 5125) $PN 22
J 0
(8335 5135);
DISPLAY 0.489362 (8335 5135);
PAINT MONO (8335 5135);
FORCEPROP 0 LASTPIN (8325 5075) $PN 23
J 0
(8335 5085);
DISPLAY 0.489362 (8335 5085);
PAINT MONO (8335 5085);
FORCEPROP 0 LASTPIN (8325 5025) $PN 27
J 0
(8335 5035);
DISPLAY 0.489362 (8335 5035);
PAINT MONO (8335 5035);
FORCEPROP 0 LASTPIN (8325 4975) $PN 28
J 0
(8335 4985);
DISPLAY 0.489362 (8335 4985);
PAINT MONO (8335 4985);
FORCEPROP 0 LASTPIN (7075 5225) $PN 3
J 2
(7065 5235);
DISPLAY 0.489362 (7065 5235);
PAINT MONO (7065 5235);
FORCEPROP 0 LASTPIN (7075 5175) $PN 4
J 2
(7065 5185);
DISPLAY 0.489362 (7065 5185);
PAINT MONO (7065 5185);
FORCEPROP 0 LASTPIN (8325 4425) $PN 33
J 0
(8335 4435);
DISPLAY 0.489362 (8335 4435);
PAINT MONO (8335 4435);
FORCEPROP 0 LASTPIN (7075 4775) $PN 9
J 2
(7065 4785);
DISPLAY 0.489362 (7065 4785);
PAINT MONO (7065 4785);
FORCEPROP 0 LASTPIN (7075 4725) $PN 8
J 2
(7065 4735);
DISPLAY 0.489362 (7065 4735);
PAINT MONO (7065 4735);
FORCEPROP 0 LASTPIN (7075 4575) $PN 10
J 2
(7065 4585);
DISPLAY 0.489362 (7065 4585);
PAINT MONO (7065 4585);
FORCEPROP 0 LASTPIN (7075 4525) $PN 11
J 2
(7065 4535);
DISPLAY 0.489362 (7065 4535);
PAINT MONO (7065 4535);
FORCEPROP 0 LASTPIN (7075 4475) $PN 17
J 2
(7065 4485);
DISPLAY 0.489362 (7065 4485);
PAINT MONO (7065 4485);
FORCEPROP 0 LASTPIN (7075 4425) $PN 30
J 2
(7065 4435);
DISPLAY 0.489362 (7065 4435);
PAINT MONO (7065 4435);
FORCEPROP 0 LASTPIN (7075 4925) $PN 7
J 2
(7065 4935);
DISPLAY 0.489362 (7065 4935);
PAINT MONO (7065 4935);
FORCEPROP 0 LASTPIN (7075 4975) $PN 6
J 2
(7065 4985);
DISPLAY 0.489362 (7065 4985);
PAINT MONO (7065 4985);
FORCEPROP 0 LASTPIN (7075 5675) $PN 12
J 2
(7065 5685);
DISPLAY 0.489362 (7065 5685);
PAINT MONO (7065 5685);
FORCEPROP 0 LASTPIN (7075 5625) $PN 16
J 2
(7065 5635);
DISPLAY 0.489362 (7065 5635);
PAINT MONO (7065 5635);
FORCEPROP 0 LASTPIN (7075 5575) $PN 21
J 2
(7065 5585);
DISPLAY 0.489362 (7065 5585);
PAINT MONO (7065 5585);
FORCEPROP 0 LASTPIN (7075 5525) $PN 25
J 2
(7065 5535);
DISPLAY 0.489362 (7065 5535);
PAINT MONO (7065 5535);
FORCEPROP 0 LASTPIN (7075 5475) $PN 29
J 2
(7065 5485);
DISPLAY 0.489362 (7065 5485);
PAINT MONO (7065 5485);
FORCEPROP 0 LASTPIN (8325 5675) $PN 31
J 0
(8335 5685);
DISPLAY 0.489362 (8335 5685);
PAINT MONO (8335 5685);
FORCEPROP 0 LASTPIN (7075 5375) $PN 2
J 2
(7065 5385);
DISPLAY 0.489362 (7065 5385);
PAINT MONO (7065 5385);
FORCEPROP 0 LASTPIN (8325 4775) $PN 15
J 0
(8335 4785);
DISPLAY 0.489362 (8335 4785);
PAINT MONO (8335 4785);
FORCEPROP 0 LASTPIN (8325 4725) $PN 18
J 0
(8335 4735);
DISPLAY 0.489362 (8335 4735);
PAINT MONO (8335 4735);
FORCEPROP 0 LASTPIN (8325 4675) $PN 24
J 0
(8335 4685);
DISPLAY 0.489362 (8335 4685);
PAINT MONO (8335 4685);
FORCEPROP 0 LASTPIN (8325 4625) $PN 26
J 0
(8335 4635);
DISPLAY 0.489362 (8335 4635);
PAINT MONO (8335 4635);
FORCEPROP 0 LASTPIN (7075 5075) $PN 5
J 2
(7065 5085);
DISPLAY 0.489362 (7065 5085);
PAINT MONO (7065 5085);
FORCEPROP 2 LAST PART_TYPE SMLF
J 0
(7300 6425);
DISPLAY 1.021277 (7300 6425);
FORCEPROP 1 LAST MATERIAL IC
J 0
(7234 5791);
DISPLAY 0.489362 (7234 5791);
PAINT SKYBLUE (7234 5791);
FORCEPROP 2 LAST VALUE 9ZXL0451EKILFT
J 0
(7300 6375);
DISPLAY 0.489362 (7300 6375);
PAINT SKYBLUE (7300 6375);
FORCEPROP 1 LAST PART_NUMBER AL000451003
J 0
(7234 5918);
DISPLAY 0.489362 (7234 5918);
PAINT SKYBLUE (7234 5918);
FORCEPROP 1 LAST NEEDS_NO_SIZE TRUE
J 0
(7700 5050);
DISPLAY 0.723404 (7700 5050);
PAINT GREEN (7700 5050);
DISPLAY INVISIBLE (7700 5050);
FORCEPROP 2 LAST CDS_LIB pure_quanta
J 0
(7700 5050);
DISPLAY INVISIBLE (7700 5050);
FORCEPROP 1 LAST CDS_LMAN_SYM_OUTLINE -475,725,475,-725
J 0
(7700 5050);
DISPLAY 0.468085 (7700 5050);
PAINT GREEN (7700 5050);
DISPLAY INVISIBLE (7700 5050);
FORCEPROP 1 LAST PATH I246
J 0
(7700 5050);
DISPLAY 0.723404 (7700 5050);
PAINT GREEN (7700 5050);
DISPLAY INVISIBLE (7700 5050);
FORCEADD VCC_CORE..1
(6450 5625);
FORCEPROP 3 LASTPIN (6450 5575) SIG_NAME P3V3_9ZX_VDDA_0\g
J 0
(6460 5585);
DISPLAY 0.659574 (6460 5585);
PAINT MONO (6460 5585);
DISPLAY INVISIBLE (6460 5585);
FORCEPROP 1 LAST HDL_POWER P3V3_9ZX_VDDA_0
J 1
(6450 5675);
DISPLAY 0.489362 (6450 5675);
PAINT GREEN (6450 5675);
FORCEPROP 2 LAST CDS_LIB mstr_symbols
J 0
(6450 5625);
DISPLAY INVISIBLE (6450 5625);
FORCEPROP 2 LAST BOM_COST SYS_CLOCK
J 0
(6450 5775);
DISPLAY 0.808511 (6450 5775);
DISPLAY INVISIBLE (6450 5775);
FORCEPROP 1 LAST PATH I313
J 0
(6500 5650);
DISPLAY 0.872340 (6500 5650);
PAINT AQUA (6500 5650);
DISPLAY INVISIBLE (6500 5650);
FORCEPROP 0 LAST VOLTAGE 3.3
J 0
(6450 5775);
DISPLAY 1.021277 (6450 5775);
PAINT SKYBLUE (6450 5775);
DISPLAY INVISIBLE (6450 5775);
FORCEPROP 2 LAST ROOM DB2000_1_BCLK
J 0
(6450 5725);
DISPLAY 0.808511 (6450 5725);
PAINT RED (6450 5725);
DISPLAY INVISIBLE (6450 5725);
FORCEADD VCC_CORE..1
(8450 6000);
FORCEPROP 3 LASTPIN (8450 5950) SIG_NAME P3V3_9ZX_VDDA_0\g
J 0
(8460 5960);
DISPLAY 0.659574 (8460 5960);
PAINT MONO (8460 5960);
DISPLAY INVISIBLE (8460 5960);
FORCEPROP 1 LAST HDL_POWER P3V3_9ZX_VDDA_0
J 1
(8450 6050);
DISPLAY 0.489362 (8450 6050);
PAINT GREEN (8450 6050);
FORCEPROP 2 LAST CDS_LIB pure_quanta_power
J 0
(8450 6000);
DISPLAY INVISIBLE (8450 6000);
FORCEPROP 2 LAST BOM_COST SYS_CLOCK
J 0
(8450 6150);
DISPLAY 0.808511 (8450 6150);
DISPLAY INVISIBLE (8450 6150);
FORCEPROP 1 LAST PATH I314
J 0
(8500 6025);
DISPLAY 0.872340 (8500 6025);
PAINT AQUA (8500 6025);
DISPLAY INVISIBLE (8500 6025);
FORCEPROP 0 LAST VOLTAGE 3.3
J 0
(8450 6150);
DISPLAY 1.021277 (8450 6150);
PAINT SKYBLUE (8450 6150);
DISPLAY INVISIBLE (8450 6150);
FORCEPROP 2 LAST ROOM DB2000_1_BCLK
J 0
(8450 6100);
DISPLAY 0.808511 (8450 6100);
PAINT RED (8450 6100);
DISPLAY INVISIBLE (8450 6100);
FORCEADD UNIVERSAL_POWER..1
(6850 6000);
FORCEPROP 3 LASTPIN (6850 5950) SIG_NAME P3V3_9ZX_VDD_0\g
J 0
(6860 5960);
DISPLAY 0.659574 (6860 5960);
PAINT MONO (6860 5960);
DISPLAY INVISIBLE (6860 5960);
FORCEPROP 1 LAST HDL_POWER P3V3_9ZX_VDD_0
J 1
(6850 6050);
DISPLAY 0.489362 (6850 6050);
PAINT GREEN (6850 6050);
FORCEPROP 2 LAST CDS_LIB mstr_symbols
J 0
(6850 6000);
DISPLAY INVISIBLE (6850 6000);
FORCEPROP 2 LAST BOM_COST SYS_CLOCK
J 0
(6850 6150);
DISPLAY 0.808511 (6850 6150);
DISPLAY INVISIBLE (6850 6150);
FORCEPROP 1 LAST PATH I315
J 0
(6900 6025);
DISPLAY 0.872340 (6900 6025);
PAINT AQUA (6900 6025);
DISPLAY INVISIBLE (6900 6025);
FORCEPROP 0 LAST VOLTAGE 3.3
J 0
(6850 6150);
DISPLAY 1.021277 (6850 6150);
PAINT SKYBLUE (6850 6150);
DISPLAY INVISIBLE (6850 6150);
FORCEPROP 2 LAST ROOM DB2000_1_BCLK
J 0
(6850 6100);
DISPLAY 0.808511 (6850 6100);
PAINT RED (6850 6100);
DISPLAY INVISIBLE (6850 6100);
FORCEADD VCC_CORE..1
(8475 2825);
FORCEPROP 3 LASTPIN (8475 2775) SIG_NAME P3V3_9ZX_VDDA_1\g
J 0
(8485 2785);
DISPLAY 0.659574 (8485 2785);
PAINT MONO (8485 2785);
DISPLAY INVISIBLE (8485 2785);
FORCEPROP 1 LAST HDL_POWER P3V3_9ZX_VDDA_1
J 1
(8475 2875);
DISPLAY 0.489362 (8475 2875);
PAINT GREEN (8475 2875);
FORCEPROP 2 LAST BOM_COST SYS_CLOCK
J 0
(8475 2975);
DISPLAY 0.808511 (8475 2975);
DISPLAY INVISIBLE (8475 2975);
FORCEPROP 2 LAST CDS_LIB pure_quanta_power
J 0
(8475 2825);
DISPLAY INVISIBLE (8475 2825);
FORCEPROP 1 LAST PATH I316
J 0
(8525 2850);
DISPLAY 0.872340 (8525 2850);
PAINT AQUA (8525 2850);
DISPLAY INVISIBLE (8525 2850);
FORCEPROP 0 LAST VOLTAGE 3.3
J 0
(8475 2975);
DISPLAY 1.021277 (8475 2975);
PAINT SKYBLUE (8475 2975);
DISPLAY INVISIBLE (8475 2975);
FORCEPROP 2 LAST ROOM DB2000_1_BCLK
J 0
(8475 2925);
DISPLAY 0.808511 (8475 2925);
PAINT RED (8475 2925);
DISPLAY INVISIBLE (8475 2925);
FORCEADD UNIVERSAL_POWER..1
(6875 2825);
FORCEPROP 3 LASTPIN (6875 2775) SIG_NAME P3V3_9ZX_VDD_1\g
J 0
(6885 2785);
DISPLAY 0.659574 (6885 2785);
PAINT MONO (6885 2785);
DISPLAY INVISIBLE (6885 2785);
FORCEPROP 1 LAST HDL_POWER P3V3_9ZX_VDD_1
J 1
(6875 2875);
DISPLAY 0.489362 (6875 2875);
PAINT GREEN (6875 2875);
FORCEPROP 2 LAST BOM_COST SYS_CLOCK
J 0
(6875 2975);
DISPLAY 0.808511 (6875 2975);
DISPLAY INVISIBLE (6875 2975);
FORCEPROP 2 LAST CDS_LIB mstr_symbols
J 0
(6875 2825);
DISPLAY INVISIBLE (6875 2825);
FORCEPROP 1 LAST PATH I317
J 0
(6925 2850);
DISPLAY 0.872340 (6925 2850);
PAINT AQUA (6925 2850);
DISPLAY INVISIBLE (6925 2850);
FORCEPROP 0 LAST VOLTAGE 3.3
J 0
(6875 2975);
DISPLAY 1.021277 (6875 2975);
PAINT SKYBLUE (6875 2975);
DISPLAY INVISIBLE (6875 2975);
FORCEPROP 2 LAST ROOM DB2000_1_BCLK
J 0
(6875 2925);
DISPLAY 0.808511 (6875 2925);
PAINT RED (6875 2925);
DISPLAY INVISIBLE (6875 2925);
FORCEADD VCC_CORE..1
(6475 2450);
FORCEPROP 3 LASTPIN (6475 2400) SIG_NAME P3V3_9ZX_VDDA_1\g
J 0
(6485 2410);
DISPLAY 0.659574 (6485 2410);
PAINT MONO (6485 2410);
DISPLAY INVISIBLE (6485 2410);
FORCEPROP 1 LAST HDL_POWER P3V3_9ZX_VDDA_1
J 1
(6475 2500);
DISPLAY 0.489362 (6475 2500);
PAINT GREEN (6475 2500);
FORCEPROP 2 LAST BOM_COST SYS_CLOCK
J 0
(6475 2600);
DISPLAY 0.808511 (6475 2600);
DISPLAY INVISIBLE (6475 2600);
FORCEPROP 2 LAST CDS_LIB mstr_symbols
J 0
(6475 2450);
DISPLAY INVISIBLE (6475 2450);
FORCEPROP 1 LAST PATH I318
J 0
(6525 2475);
DISPLAY 0.872340 (6525 2475);
PAINT AQUA (6525 2475);
DISPLAY INVISIBLE (6525 2475);
FORCEPROP 0 LAST VOLTAGE 3.3
J 0
(6475 2600);
DISPLAY 1.021277 (6475 2600);
PAINT SKYBLUE (6475 2600);
DISPLAY INVISIBLE (6475 2600);
FORCEPROP 2 LAST ROOM DB2000_1_BCLK
J 0
(6475 2550);
DISPLAY 0.808511 (6475 2550);
PAINT RED (6475 2550);
DISPLAY INVISIBLE (6475 2550);
FORCEADD OFFPAGE..1
(6250 2050);
FORCEPROP 2 LAST $XR0 55 
J 0
(6029 2050);
DISPLAY 0.638298 (6029 2050);
PAINT MONO (6029 2050);
FORCEPROP 1 LAST OFFPAGE TRUE
J 0
(6575 1925);
DISPLAY 0.872340 (6575 1925);
PAINT GREEN (6575 1925);
DISPLAY INVISIBLE (6575 1925);
FORCEPROP 1 LAST COMMENT_BODY TRUE
J 0
(6375 1950);
DISPLAY 0.872340 (6375 1950);
PAINT GREEN (6375 1950);
DISPLAY INVISIBLE (6375 1950);
FORCEPROP 2 LAST PATH I319
J 0
(6300 2125);
DISPLAY 1.021277 (6300 2125);
DISPLAY INVISIBLE (6300 2125);
FORCEPROP 2 LAST CDS_LIB standard
J 0
(6250 2050);
DISPLAY INVISIBLE (6250 2050);
FORCEADD OFFPAGE..1
(6250 2000);
FORCEPROP 2 LAST $XR0 55 
J 0
(6029 2000);
DISPLAY 0.638298 (6029 2000);
PAINT MONO (6029 2000);
FORCEPROP 2 LAST CDS_LIB standard
J 0
(6250 2000);
DISPLAY INVISIBLE (6250 2000);
FORCEPROP 2 LAST PATH I320
J 0
(6300 2075);
DISPLAY 1.021277 (6300 2075);
DISPLAY INVISIBLE (6300 2075);
FORCEPROP 1 LAST COMMENT_BODY TRUE
J 0
(6375 1900);
DISPLAY 0.872340 (6375 1900);
PAINT GREEN (6375 1900);
DISPLAY INVISIBLE (6375 1900);
FORCEPROP 1 LAST OFFPAGE TRUE
J 0
(6575 1875);
DISPLAY 0.872340 (6575 1875);
PAINT GREEN (6575 1875);
DISPLAY INVISIBLE (6575 1875);
FORCEADD OFFPAGE..1
(6225 5175);
FORCEPROP 2 LAST $XR0 28 
J 0
(6004 5175);
DISPLAY 0.638298 (6004 5175);
PAINT MONO (6004 5175);
FORCEPROP 1 LAST COMMENT_BODY TRUE
J 0
(6350 5075);
DISPLAY 0.872340 (6350 5075);
PAINT GREEN (6350 5075);
DISPLAY INVISIBLE (6350 5075);
FORCEPROP 1 LAST OFFPAGE TRUE
J 0
(6550 5050);
DISPLAY 0.872340 (6550 5050);
PAINT GREEN (6550 5050);
DISPLAY INVISIBLE (6550 5050);
FORCEPROP 2 LAST PATH I321
J 0
(6275 5250);
DISPLAY 1.021277 (6275 5250);
DISPLAY INVISIBLE (6275 5250);
FORCEPROP 2 LAST CDS_LIB standard
J 0
(6225 5175);
DISPLAY INVISIBLE (6225 5175);
FORCEADD OFFPAGE..1
(6225 5225);
FORCEPROP 2 LAST $XR0 28 
J 0
(6004 5225);
DISPLAY 0.638298 (6004 5225);
PAINT MONO (6004 5225);
FORCEPROP 1 LAST COMMENT_BODY TRUE
J 0
(6350 5125);
DISPLAY 0.872340 (6350 5125);
PAINT GREEN (6350 5125);
DISPLAY INVISIBLE (6350 5125);
FORCEPROP 1 LAST OFFPAGE TRUE
J 0
(6550 5100);
DISPLAY 0.872340 (6550 5100);
PAINT GREEN (6550 5100);
DISPLAY INVISIBLE (6550 5100);
FORCEPROP 2 LAST PATH I322
J 0
(6275 5300);
DISPLAY 1.021277 (6275 5300);
DISPLAY INVISIBLE (6275 5300);
FORCEPROP 2 LAST CDS_LIB standard
J 0
(6225 5225);
DISPLAY INVISIBLE (6225 5225);
FORCEADD UNIVERSAL_GND..1
(2325 4475);
FORCEPROP 3 LASTPIN (2325 4525) SIG_NAME GND\g
J 0
(2335 4535);
DISPLAY 0.659574 (2335 4535);
PAINT MONO (2335 4535);
DISPLAY INVISIBLE (2335 4535);
FORCEPROP 1 LAST HDL_POWER GND
J 1
(2350 4400);
DISPLAY 0.489362 (2350 4400);
PAINT GREEN (2350 4400);
FORCEPROP 2 LAST CDS_LIB pure_quanta_power
J 0
(2325 4475);
DISPLAY INVISIBLE (2325 4475);
FORCEPROP 1 LAST PATH I323
J 0
(2400 4475);
DISPLAY 0.872340 (2400 4475);
PAINT AQUA (2400 4475);
DISPLAY INVISIBLE (2400 4475);
FORCEADD Q_CAP..1
(2325 4760);
FORCEPROP 1 LAST LOCATION C1193
J 0
(2375 4860);
DISPLAY 0.489362 (2375 4860);
PAINT SKYBLUE (2375 4860);
FORCEPROP 0 LAST $SEC 1
J 0
(2375 4925);
DISPLAY 0.680851 (2375 4925);
PAINT MONO (2375 4925);
DISPLAY INVISIBLE (2375 4925);
FORCEPROP 0 LAST CDS_SEC 1
J 0
(2375 4925);
DISPLAY 1.021277 (2375 4925);
DISPLAY INVISIBLE (2375 4925);
FORCEPROP 1 LASTPIN (2325 4860) $PN 1
J 0
(2335 4840);
DISPLAY 0.489362 (2335 4840);
PAINT MONO (2335 4840);
FORCEPROP 1 LASTPIN (2325 4660) $PN 2
J 0
(2335 4640);
DISPLAY 0.489362 (2335 4640);
PAINT MONO (2335 4640);
FORCEPROP 1 LAST MATERIAL X6S
J 0
(2375 4660);
DISPLAY 0.489362 (2375 4660);
PAINT SKYBLUE (2375 4660);
FORCEPROP 1 LAST TOLERANCE 10%
J 0
(2375 4710);
DISPLAY 0.489362 (2375 4710);
PAINT SKYBLUE (2375 4710);
FORCEPROP 1 LAST VALUE 1UF
J 0
(2375 4810);
DISPLAY 0.489362 (2375 4810);
PAINT SKYBLUE (2375 4810);
FORCEPROP 1 LAST VOLTAGE 25V
J 0
(2375 4760);
DISPLAY 0.489362 (2375 4760);
PAINT SKYBLUE (2375 4760);
FORCEPROP 1 LAST PACK_TYPE C0402
J 0
(2375 4610);
DISPLAY 0.489362 (2375 4610);
PAINT SKYBLUE (2375 4610);
FORCEPROP 2 LAST CDS_LIB pure_quanta
J 0
(2325 4760);
DISPLAY INVISIBLE (2325 4760);
FORCEPROP 1 LAST PATH I324
J 0
(2375 4910);
DISPLAY 0.978723 (2375 4910);
PAINT WHITE (2375 4910);
DISPLAY INVISIBLE (2375 4910);
FORCEPROP 1 LAST PART_NUMBER CH5104KEB02
J 0
(2375 4610);
DISPLAY 0.617021 (2375 4610);
PAINT SKYBLUE (2375 4610);
DISPLAY INVISIBLE (2375 4610);
FORCEADD UNIVERSAL_GND..1
(2725 4450);
FORCEPROP 3 LASTPIN (2725 4500) SIG_NAME GND\g
J 0
(2735 4510);
DISPLAY 0.659574 (2735 4510);
PAINT MONO (2735 4510);
DISPLAY INVISIBLE (2735 4510);
FORCEPROP 1 LAST HDL_POWER GND
J 1
(2750 4375);
DISPLAY 0.489362 (2750 4375);
PAINT GREEN (2750 4375);
FORCEPROP 2 LAST CDS_LIB pure_quanta_power
J 0
(2725 4450);
DISPLAY INVISIBLE (2725 4450);
FORCEPROP 1 LAST PATH I326
J 0
(2800 4450);
DISPLAY 0.872340 (2800 4450);
PAINT AQUA (2800 4450);
DISPLAY INVISIBLE (2800 4450);
FORCEADD UNIVERSAL_GND..1
(2975 4450);
FORCEPROP 3 LASTPIN (2975 4500) SIG_NAME GND\g
J 0
(2985 4510);
DISPLAY 0.659574 (2985 4510);
PAINT MONO (2985 4510);
DISPLAY INVISIBLE (2985 4510);
FORCEPROP 1 LAST HDL_POWER GND
J 1
(3000 4375);
DISPLAY 0.489362 (3000 4375);
PAINT GREEN (3000 4375);
FORCEPROP 2 LAST CDS_LIB pure_quanta_power
J 0
(2975 4450);
DISPLAY INVISIBLE (2975 4450);
FORCEPROP 1 LAST PATH I327
J 0
(3050 4450);
DISPLAY 0.872340 (3050 4450);
PAINT AQUA (3050 4450);
DISPLAY INVISIBLE (3050 4450);
FORCEADD Q_CAP..1
(2725 4725);
FORCEPROP 1 LAST LOCATION C1197
J 0
(2775 4825);
DISPLAY 0.489362 (2775 4825);
PAINT SKYBLUE (2775 4825);
FORCEPROP 0 LAST $SEC 1
J 0
(2775 4875);
DISPLAY 0.680851 (2775 4875);
PAINT MONO (2775 4875);
DISPLAY INVISIBLE (2775 4875);
FORCEPROP 0 LAST CDS_SEC 1
J 0
(2775 4875);
DISPLAY 1.021277 (2775 4875);
DISPLAY INVISIBLE (2775 4875);
FORCEPROP 1 LASTPIN (2725 4825) $PN 1
J 0
(2735 4805);
DISPLAY 0.489362 (2735 4805);
PAINT MONO (2735 4805);
FORCEPROP 1 LASTPIN (2725 4625) $PN 2
J 0
(2735 4605);
DISPLAY 0.489362 (2735 4605);
PAINT MONO (2735 4605);
FORCEPROP 1 LAST MATERIAL X7R
J 0
(2775 4625);
DISPLAY 0.489362 (2775 4625);
PAINT SKYBLUE (2775 4625);
FORCEPROP 1 LAST TOLERANCE 10%
J 0
(2775 4675);
DISPLAY 0.489362 (2775 4675);
PAINT SKYBLUE (2775 4675);
FORCEPROP 1 LAST VALUE 0.1UF
J 0
(2775 4775);
DISPLAY 0.489362 (2775 4775);
PAINT SKYBLUE (2775 4775);
FORCEPROP 1 LAST VOLTAGE 25V
J 0
(2775 4725);
DISPLAY 0.489362 (2775 4725);
PAINT SKYBLUE (2775 4725);
FORCEPROP 1 LAST PACK_TYPE 0402
J 0
(2775 4575);
DISPLAY 0.489362 (2775 4575);
PAINT SKYBLUE (2775 4575);
FORCEPROP 2 LAST CDS_LIB pure_quanta
J 0
(2725 4725);
DISPLAY INVISIBLE (2725 4725);
FORCEPROP 1 LAST PATH I328
J 0
(2775 4875);
DISPLAY 0.978723 (2775 4875);
PAINT WHITE (2775 4875);
DISPLAY INVISIBLE (2775 4875);
FORCEPROP 1 LAST PART_NUMBER CH4104K1B00
J 0
(2775 4575);
DISPLAY 0.978723 (2775 4575);
PAINT SKYBLUE (2775 4575);
DISPLAY INVISIBLE (2775 4575);
FORCEADD Q_CAP..1
(2975 4725);
FORCEPROP 1 LAST LOCATION C1202
J 0
(3025 4825);
DISPLAY 0.489362 (3025 4825);
PAINT SKYBLUE (3025 4825);
FORCEPROP 0 LAST $SEC 1
J 0
(3025 4875);
DISPLAY 0.680851 (3025 4875);
PAINT MONO (3025 4875);
DISPLAY INVISIBLE (3025 4875);
FORCEPROP 0 LAST CDS_SEC 1
J 0
(3025 4875);
DISPLAY 1.021277 (3025 4875);
DISPLAY INVISIBLE (3025 4875);
FORCEPROP 1 LASTPIN (2975 4825) $PN 1
J 0
(2985 4805);
DISPLAY 0.489362 (2985 4805);
PAINT MONO (2985 4805);
FORCEPROP 1 LASTPIN (2975 4625) $PN 2
J 0
(2985 4605);
DISPLAY 0.489362 (2985 4605);
PAINT MONO (2985 4605);
FORCEPROP 1 LAST MATERIAL X7R
J 0
(3025 4625);
DISPLAY 0.489362 (3025 4625);
PAINT SKYBLUE (3025 4625);
FORCEPROP 1 LAST TOLERANCE 10%
J 0
(3025 4675);
DISPLAY 0.489362 (3025 4675);
PAINT SKYBLUE (3025 4675);
FORCEPROP 1 LAST VALUE 0.1UF
J 0
(3025 4775);
DISPLAY 0.489362 (3025 4775);
PAINT SKYBLUE (3025 4775);
FORCEPROP 1 LAST VOLTAGE 25V
J 0
(3025 4725);
DISPLAY 0.489362 (3025 4725);
PAINT SKYBLUE (3025 4725);
FORCEPROP 1 LAST PACK_TYPE 0402
J 0
(3025 4575);
DISPLAY 0.489362 (3025 4575);
PAINT SKYBLUE (3025 4575);
FORCEPROP 2 LAST CDS_LIB pure_quanta
J 0
(2975 4725);
DISPLAY INVISIBLE (2975 4725);
FORCEPROP 1 LAST PATH I330
J 0
(3025 4875);
DISPLAY 0.978723 (3025 4875);
PAINT WHITE (3025 4875);
DISPLAY INVISIBLE (3025 4875);
FORCEPROP 1 LAST PART_NUMBER CH4104K1B00
J 0
(3025 4575);
DISPLAY 0.978723 (3025 4575);
PAINT SKYBLUE (3025 4575);
DISPLAY INVISIBLE (3025 4575);
FORCEADD UNIVERSAL_GND..1
(3200 4450);
FORCEPROP 3 LASTPIN (3200 4500) SIG_NAME GND\g
J 0
(3210 4510);
DISPLAY 0.659574 (3210 4510);
PAINT MONO (3210 4510);
DISPLAY INVISIBLE (3210 4510);
FORCEPROP 1 LAST HDL_POWER GND
J 1
(3225 4375);
DISPLAY 0.489362 (3225 4375);
PAINT GREEN (3225 4375);
FORCEPROP 2 LAST CDS_LIB pure_quanta_power
J 0
(3200 4450);
DISPLAY INVISIBLE (3200 4450);
FORCEPROP 1 LAST PATH I332
J 0
(3275 4450);
DISPLAY 0.872340 (3275 4450);
PAINT AQUA (3275 4450);
DISPLAY INVISIBLE (3275 4450);
FORCEADD UNIVERSAL_GND..1
(3430 4445);
FORCEPROP 3 LASTPIN (3430 4495) SIG_NAME GND\g
J 0
(3440 4505);
DISPLAY 0.659574 (3440 4505);
PAINT MONO (3440 4505);
DISPLAY INVISIBLE (3440 4505);
FORCEPROP 1 LAST HDL_POWER GND
J 1
(3455 4370);
DISPLAY 0.489362 (3455 4370);
PAINT GREEN (3455 4370);
FORCEPROP 2 LAST CDS_LIB pure_quanta_power
J 0
(3430 4445);
DISPLAY INVISIBLE (3430 4445);
FORCEPROP 1 LAST PATH I333
J 0
(3505 4445);
DISPLAY 0.872340 (3505 4445);
PAINT AQUA (3505 4445);
DISPLAY INVISIBLE (3505 4445);
FORCEADD Q_CAP..1
(3200 4725);
FORCEPROP 1 LAST LOCATION C1206
J 0
(3250 4825);
DISPLAY 0.489362 (3250 4825);
PAINT SKYBLUE (3250 4825);
FORCEPROP 0 LAST $SEC 1
J 0
(3250 4875);
DISPLAY 0.680851 (3250 4875);
PAINT MONO (3250 4875);
DISPLAY INVISIBLE (3250 4875);
FORCEPROP 0 LAST CDS_SEC 1
J 0
(3250 4875);
DISPLAY 1.021277 (3250 4875);
DISPLAY INVISIBLE (3250 4875);
FORCEPROP 1 LASTPIN (3200 4825) $PN 1
J 0
(3210 4805);
DISPLAY 0.489362 (3210 4805);
PAINT MONO (3210 4805);
FORCEPROP 1 LASTPIN (3200 4625) $PN 2
J 0
(3210 4605);
DISPLAY 0.489362 (3210 4605);
PAINT MONO (3210 4605);
FORCEPROP 1 LAST MATERIAL X7R
J 0
(3250 4625);
DISPLAY 0.489362 (3250 4625);
PAINT SKYBLUE (3250 4625);
FORCEPROP 1 LAST TOLERANCE 10%
J 0
(3250 4675);
DISPLAY 0.489362 (3250 4675);
PAINT SKYBLUE (3250 4675);
FORCEPROP 1 LAST VALUE 0.1UF
J 0
(3250 4775);
DISPLAY 0.489362 (3250 4775);
PAINT SKYBLUE (3250 4775);
FORCEPROP 1 LAST VOLTAGE 25V
J 0
(3250 4725);
DISPLAY 0.489362 (3250 4725);
PAINT SKYBLUE (3250 4725);
FORCEPROP 1 LAST PACK_TYPE 0402
J 0
(3250 4575);
DISPLAY 0.489362 (3250 4575);
PAINT SKYBLUE (3250 4575);
FORCEPROP 2 LAST CDS_LIB pure_quanta
J 0
(3200 4725);
DISPLAY INVISIBLE (3200 4725);
FORCEPROP 1 LAST PATH I334
J 0
(3250 4875);
DISPLAY 0.978723 (3250 4875);
PAINT WHITE (3250 4875);
DISPLAY INVISIBLE (3250 4875);
FORCEPROP 1 LAST PART_NUMBER CH4104K1B00
J 0
(3250 4575);
DISPLAY 0.978723 (3250 4575);
PAINT SKYBLUE (3250 4575);
DISPLAY INVISIBLE (3250 4575);
FORCEADD Q_CAP..1
(3430 4720);
FORCEPROP 1 LAST LOCATION C1209
J 0
(3480 4820);
DISPLAY 0.489362 (3480 4820);
PAINT SKYBLUE (3480 4820);
FORCEPROP 0 LAST $SEC 1
J 0
(3500 4875);
DISPLAY 0.680851 (3500 4875);
PAINT MONO (3500 4875);
DISPLAY INVISIBLE (3500 4875);
FORCEPROP 0 LAST CDS_SEC 1
J 0
(3500 4875);
DISPLAY 1.021277 (3500 4875);
DISPLAY INVISIBLE (3500 4875);
FORCEPROP 1 LASTPIN (3430 4820) $PN 1
J 0
(3440 4800);
DISPLAY 0.489362 (3440 4800);
PAINT MONO (3440 4800);
FORCEPROP 1 LASTPIN (3430 4620) $PN 2
J 0
(3440 4600);
DISPLAY 0.489362 (3440 4600);
PAINT MONO (3440 4600);
FORCEPROP 1 LAST MATERIAL X7R
J 0
(3480 4620);
DISPLAY 0.489362 (3480 4620);
PAINT SKYBLUE (3480 4620);
FORCEPROP 1 LAST TOLERANCE 10%
J 0
(3480 4670);
DISPLAY 0.489362 (3480 4670);
PAINT SKYBLUE (3480 4670);
FORCEPROP 1 LAST VALUE 0.1UF
J 0
(3480 4770);
DISPLAY 0.489362 (3480 4770);
PAINT SKYBLUE (3480 4770);
FORCEPROP 1 LAST VOLTAGE 25V
J 0
(3480 4720);
DISPLAY 0.489362 (3480 4720);
PAINT SKYBLUE (3480 4720);
FORCEPROP 1 LAST PACK_TYPE 0402
J 0
(3480 4570);
DISPLAY 0.489362 (3480 4570);
PAINT SKYBLUE (3480 4570);
FORCEPROP 2 LAST CDS_LIB pure_quanta
J 0
(3430 4720);
DISPLAY INVISIBLE (3430 4720);
FORCEPROP 1 LAST PATH I336
J 0
(3480 4870);
DISPLAY 0.978723 (3480 4870);
PAINT WHITE (3480 4870);
DISPLAY INVISIBLE (3480 4870);
FORCEPROP 1 LAST PART_NUMBER CH4104K1B00
J 0
(3480 4570);
DISPLAY 0.978723 (3480 4570);
PAINT SKYBLUE (3480 4570);
DISPLAY INVISIBLE (3480 4570);
FORCEADD Q_INDUCTOR..1
(2150 5425);
FORCEPROP 1 LAST LOCATION L6
J 0
(2025 5585);
DISPLAY 0.489362 (2025 5585);
PAINT SKYBLUE (2025 5585);
FORCEPROP 0 LAST $SEC 1
J 0
(2025 5700);
DISPLAY 0.680851 (2025 5700);
PAINT MONO (2025 5700);
DISPLAY INVISIBLE (2025 5700);
FORCEPROP 0 LAST CDS_SEC 1
J 0
(2025 5700);
DISPLAY 1.021277 (2025 5700);
DISPLAY INVISIBLE (2025 5700);
FORCEPROP 0 LASTPIN (2050 5400) $PN 1
J 2
(2040 5410);
DISPLAY 0.489362 (2040 5410);
PAINT MONO (2040 5410);
FORCEPROP 0 LASTPIN (2250 5400) $PN 2
J 0
(2260 5410);
DISPLAY 0.489362 (2260 5410);
PAINT MONO (2260 5410);
FORCEPROP 1 LAST MATERIAL IND
J 0
(2025 5480);
DISPLAY 0.489362 (2025 5480);
PAINT SKYBLUE (2025 5480);
FORCEPROP 2 LAST VALUE 330/2.5A
J 0
(2025 5625);
DISPLAY 0.489362 (2025 5625);
PAINT SKYBLUE (2025 5625);
FORCEPROP 1 LAST PART_NUMBER CX12S331000
J 0
(2025 5535);
DISPLAY 0.489362 (2025 5535);
PAINT SKYBLUE (2025 5535);
FORCEPROP 2 LAST PACK_TYPE SMLF
J 0
(2025 5675);
DISPLAY 0.489362 (2025 5675);
PAINT SKYBLUE (2025 5675);
FORCEPROP 1 LAST NEEDS_NO_SIZE TRUE
J 0
(2150 5425);
DISPLAY 0.468085 (2150 5425);
PAINT GREEN (2150 5425);
DISPLAY INVISIBLE (2150 5425);
FORCEPROP 2 LAST CDS_LIB pure_quanta
J 0
(2150 5425);
DISPLAY INVISIBLE (2150 5425);
FORCEPROP 1 LAST PATH I337
J 0
(2225 5480);
DISPLAY 0.723404 (2225 5480);
PAINT GREEN (2225 5480);
DISPLAY INVISIBLE (2225 5480);
FORCEADD UNIVERSAL_POWER..1
(1800 5550);
FORCEPROP 3 LASTPIN (1800 5500) SIG_NAME P3V3\g
J 0
(1810 5510);
DISPLAY 0.659574 (1810 5510);
PAINT MONO (1810 5510);
DISPLAY INVISIBLE (1810 5510);
FORCEPROP 1 LAST HDL_POWER P3V3
J 1
(1800 5600);
DISPLAY 0.489362 (1800 5600);
PAINT GREEN (1800 5600);
FORCEPROP 2 LAST CDS_LIB pure_quanta_power
J 0
(1800 5550);
DISPLAY INVISIBLE (1800 5550);
FORCEPROP 1 LAST PATH I338
J 0
(1850 5575);
DISPLAY 0.872340 (1850 5575);
PAINT AQUA (1850 5575);
DISPLAY INVISIBLE (1850 5575);
FORCEADD UNIVERSAL_POWER..1
(3475 5600);
FORCEPROP 3 LASTPIN (3475 5550) SIG_NAME P3V3_9ZX_VDD_0\g
J 0
(3485 5560);
DISPLAY 0.659574 (3485 5560);
PAINT MONO (3485 5560);
DISPLAY INVISIBLE (3485 5560);
FORCEPROP 1 LAST HDL_POWER P3V3_9ZX_VDD_0
J 1
(3475 5650);
DISPLAY 0.489362 (3475 5650);
PAINT GREEN (3475 5650);
FORCEPROP 2 LAST CDS_LIB pure_quanta_power
J 0
(3475 5600);
DISPLAY INVISIBLE (3475 5600);
FORCEPROP 2 LAST BOM_COST SYS_CLOCK
J 0
(3475 5750);
DISPLAY 0.808511 (3475 5750);
DISPLAY INVISIBLE (3475 5750);
FORCEPROP 1 LAST PATH I343
J 0
(3525 5625);
DISPLAY 0.872340 (3525 5625);
PAINT AQUA (3525 5625);
DISPLAY INVISIBLE (3525 5625);
FORCEPROP 0 LAST VOLTAGE 3.3
J 0
(3475 5750);
DISPLAY 1.021277 (3475 5750);
PAINT SKYBLUE (3475 5750);
DISPLAY INVISIBLE (3475 5750);
FORCEPROP 2 LAST ROOM DB2000_1_BCLK
J 0
(3475 5700);
DISPLAY 0.808511 (3475 5700);
PAINT RED (3475 5700);
DISPLAY INVISIBLE (3475 5700);
FORCEADD UNIVERSAL_GND..1
(3660 4440);
FORCEPROP 3 LASTPIN (3660 4490) SIG_NAME GND\g
J 0
(3670 4500);
DISPLAY 0.659574 (3670 4500);
PAINT MONO (3670 4500);
DISPLAY INVISIBLE (3670 4500);
FORCEPROP 1 LAST HDL_POWER GND
J 1
(3685 4365);
DISPLAY 0.489362 (3685 4365);
PAINT GREEN (3685 4365);
FORCEPROP 2 LAST CDS_LIB pure_quanta_power
J 0
(3660 4440);
DISPLAY INVISIBLE (3660 4440);
FORCEPROP 1 LAST PATH I344
J 0
(3735 4440);
DISPLAY 0.872340 (3735 4440);
PAINT AQUA (3735 4440);
DISPLAY INVISIBLE (3735 4440);
FORCEADD Q_CAP..1
(3660 4715);
FORCEPROP 1 LAST LOCATION C1211
J 0
(3710 4815);
DISPLAY 0.489362 (3710 4815);
PAINT SKYBLUE (3710 4815);
FORCEPROP 0 LAST $SEC 1
J 0
(3725 4875);
DISPLAY 0.680851 (3725 4875);
PAINT MONO (3725 4875);
DISPLAY INVISIBLE (3725 4875);
FORCEPROP 0 LAST CDS_SEC 1
J 0
(3725 4875);
DISPLAY 1.021277 (3725 4875);
DISPLAY INVISIBLE (3725 4875);
FORCEPROP 1 LASTPIN (3660 4815) $PN 1
J 0
(3670 4795);
DISPLAY 0.489362 (3670 4795);
PAINT MONO (3670 4795);
FORCEPROP 1 LASTPIN (3660 4615) $PN 2
J 0
(3670 4595);
DISPLAY 0.489362 (3670 4595);
PAINT MONO (3670 4595);
FORCEPROP 1 LAST MATERIAL X7R
J 0
(3710 4615);
DISPLAY 0.489362 (3710 4615);
PAINT SKYBLUE (3710 4615);
FORCEPROP 1 LAST TOLERANCE 10%
J 0
(3710 4665);
DISPLAY 0.489362 (3710 4665);
PAINT SKYBLUE (3710 4665);
FORCEPROP 1 LAST VALUE 0.1UF
J 0
(3710 4765);
DISPLAY 0.489362 (3710 4765);
PAINT SKYBLUE (3710 4765);
FORCEPROP 1 LAST VOLTAGE 25V
J 0
(3710 4715);
DISPLAY 0.489362 (3710 4715);
PAINT SKYBLUE (3710 4715);
FORCEPROP 1 LAST PACK_TYPE 0402
J 0
(3710 4565);
DISPLAY 0.489362 (3710 4565);
PAINT SKYBLUE (3710 4565);
FORCEPROP 2 LAST CDS_LIB pure_quanta
J 0
(3660 4715);
DISPLAY INVISIBLE (3660 4715);
FORCEPROP 1 LAST PATH I346
J 0
(3710 4865);
DISPLAY 0.978723 (3710 4865);
PAINT WHITE (3710 4865);
DISPLAY INVISIBLE (3710 4865);
FORCEPROP 1 LAST PART_NUMBER CH4104K1B00
J 0
(3710 4565);
DISPLAY 0.978723 (3710 4565);
PAINT SKYBLUE (3710 4565);
DISPLAY INVISIBLE (3710 4565);
FORCEADD UNIVERSAL_GND..1
(4225 4975);
FORCEPROP 3 LASTPIN (4225 5025) SIG_NAME GND\g
J 0
(4235 5035);
DISPLAY 0.659574 (4235 5035);
PAINT MONO (4235 5035);
DISPLAY INVISIBLE (4235 5035);
FORCEPROP 1 LAST HDL_POWER GND
J 1
(4250 4900);
DISPLAY 0.489362 (4250 4900);
PAINT GREEN (4250 4900);
FORCEPROP 2 LAST CDS_LIB pure_quanta_power
J 0
(4225 4975);
DISPLAY INVISIBLE (4225 4975);
FORCEPROP 1 LAST PATH I348
J 0
(4300 4975);
DISPLAY 0.872340 (4300 4975);
PAINT AQUA (4300 4975);
DISPLAY INVISIBLE (4300 4975);
FORCEADD UNIVERSAL_GND..1
(4475 4975);
FORCEPROP 3 LASTPIN (4475 5025) SIG_NAME GND\g
J 0
(4485 5035);
DISPLAY 0.659574 (4485 5035);
PAINT MONO (4485 5035);
DISPLAY INVISIBLE (4485 5035);
FORCEPROP 1 LAST HDL_POWER GND
J 1
(4500 4900);
DISPLAY 0.489362 (4500 4900);
PAINT GREEN (4500 4900);
FORCEPROP 2 LAST CDS_LIB pure_quanta_power
J 0
(4475 4975);
DISPLAY INVISIBLE (4475 4975);
FORCEPROP 1 LAST PATH I349
J 0
(4550 4975);
DISPLAY 0.872340 (4550 4975);
PAINT AQUA (4550 4975);
DISPLAY INVISIBLE (4550 4975);
FORCEADD UNIVERSAL_GND..1
(4675 4975);
FORCEPROP 3 LASTPIN (4675 5025) SIG_NAME GND\g
J 0
(4685 5035);
DISPLAY 0.659574 (4685 5035);
PAINT MONO (4685 5035);
DISPLAY INVISIBLE (4685 5035);
FORCEPROP 1 LAST HDL_POWER GND
J 1
(4700 4900);
DISPLAY 0.489362 (4700 4900);
PAINT GREEN (4700 4900);
FORCEPROP 2 LAST CDS_LIB pure_quanta_power
J 0
(4675 4975);
DISPLAY INVISIBLE (4675 4975);
FORCEPROP 1 LAST PATH I350
J 0
(4750 4975);
DISPLAY 0.872340 (4750 4975);
PAINT AQUA (4750 4975);
DISPLAY INVISIBLE (4750 4975);
FORCEADD Q_RES..1
(3825 5400);
FORCEPROP 1 LAST LOCATION R794
J 0
(3775 5450);
DISPLAY 0.489362 (3775 5450);
PAINT SKYBLUE (3775 5450);
FORCEPROP 0 LAST $SEC 1
J 0
(3775 5500);
DISPLAY 0.680851 (3775 5500);
PAINT MONO (3775 5500);
DISPLAY INVISIBLE (3775 5500);
FORCEPROP 0 LAST CDS_SEC 1
J 0
(3775 5500);
DISPLAY 1.021277 (3775 5500);
DISPLAY INVISIBLE (3775 5500);
FORCEPROP 1 LASTPIN (3725 5400) $PN 1
J 0
(3737 5412);
DISPLAY 0.489362 (3737 5412);
PAINT MONO (3737 5412);
FORCEPROP 1 LASTPIN (3925 5400) $PN 2
J 0
(3887 5412);
DISPLAY 0.489362 (3887 5412);
PAINT MONO (3887 5412);
FORCEPROP 1 LAST WATTAGE 1/10W
J 2
(3825 5325);
DISPLAY 0.489362 (3825 5325);
PAINT SKYBLUE (3825 5325);
FORCEPROP 1 LAST MATERIAL CHIP
J 0
(3850 5300);
DISPLAY 0.489362 (3850 5300);
PAINT SKYBLUE (3850 5300);
FORCEPROP 1 LAST TOLERANCE 1%
J 0
(3950 5450);
DISPLAY 0.489362 (3950 5450);
PAINT SKYBLUE (3950 5450);
FORCEPROP 1 LAST VALUE 1
J 2
(3750 5425);
DISPLAY 0.489362 (3750 5425);
PAINT SKYBLUE (3750 5425);
FORCEPROP 1 LAST PACK_TYPE 0603LF
J 0
(3975 5350);
DISPLAY 0.489362 (3975 5350);
PAINT SKYBLUE (3975 5350);
FORCEPROP 2 LAST CDS_LIB pure_quanta
J 0
(3825 5400);
DISPLAY INVISIBLE (3825 5400);
FORCEPROP 1 LAST PATH I351
J 0
(3775 5550);
DISPLAY 0.978723 (3775 5550);
PAINT WHITE (3775 5550);
DISPLAY INVISIBLE (3775 5550);
FORCEPROP 1 LAST PART_NUMBER CS-1003F920
J 0
(3775 5500);
DISPLAY 0.978723 (3775 5500);
PAINT SKYBLUE (3775 5500);
DISPLAY INVISIBLE (3775 5500);
FORCEADD Q_CAP..1
(4225 5250);
FORCEPROP 1 LAST LOCATION C1215
J 0
(4275 5350);
DISPLAY 0.489362 (4275 5350);
PAINT SKYBLUE (4275 5350);
FORCEPROP 0 LAST $SEC 1
J 0
(4275 5400);
DISPLAY 0.680851 (4275 5400);
PAINT MONO (4275 5400);
DISPLAY INVISIBLE (4275 5400);
FORCEPROP 0 LAST CDS_SEC 1
J 0
(4275 5400);
DISPLAY 1.021277 (4275 5400);
DISPLAY INVISIBLE (4275 5400);
FORCEPROP 1 LASTPIN (4225 5350) $PN 1
J 0
(4235 5330);
DISPLAY 0.489362 (4235 5330);
PAINT MONO (4235 5330);
FORCEPROP 1 LASTPIN (4225 5150) $PN 2
J 0
(4235 5130);
DISPLAY 0.489362 (4235 5130);
PAINT MONO (4235 5130);
FORCEPROP 1 LAST MATERIAL X6S
J 0
(4275 5150);
DISPLAY 0.489362 (4275 5150);
PAINT SKYBLUE (4275 5150);
FORCEPROP 1 LAST TOLERANCE 10%
J 0
(4275 5200);
DISPLAY 0.489362 (4275 5200);
PAINT SKYBLUE (4275 5200);
FORCEPROP 1 LAST VALUE 1UF
J 0
(4275 5300);
DISPLAY 0.489362 (4275 5300);
PAINT SKYBLUE (4275 5300);
FORCEPROP 1 LAST VOLTAGE 25V
J 0
(4275 5250);
DISPLAY 0.489362 (4275 5250);
PAINT SKYBLUE (4275 5250);
FORCEPROP 1 LAST PACK_TYPE C0402
J 0
(4275 5100);
DISPLAY 0.489362 (4275 5100);
PAINT SKYBLUE (4275 5100);
FORCEPROP 2 LAST CDS_LIB pure_quanta
J 0
(4225 5250);
DISPLAY INVISIBLE (4225 5250);
FORCEPROP 1 LAST PATH I352
J 0
(4275 5400);
DISPLAY 0.978723 (4275 5400);
PAINT WHITE (4275 5400);
DISPLAY INVISIBLE (4275 5400);
FORCEPROP 1 LAST PART_NUMBER CH5104KEB02
J 0
(4275 5100);
DISPLAY 0.617021 (4275 5100);
PAINT SKYBLUE (4275 5100);
DISPLAY INVISIBLE (4275 5100);
FORCEADD Q_CAP..1
(4475 5250);
FORCEPROP 1 LAST LOCATION C1217
J 0
(4525 5350);
DISPLAY 0.489362 (4525 5350);
PAINT SKYBLUE (4525 5350);
FORCEPROP 0 LAST $SEC 1
J 0
(4525 5400);
DISPLAY 0.680851 (4525 5400);
PAINT MONO (4525 5400);
DISPLAY INVISIBLE (4525 5400);
FORCEPROP 0 LAST CDS_SEC 1
J 0
(4525 5400);
DISPLAY 1.021277 (4525 5400);
DISPLAY INVISIBLE (4525 5400);
FORCEPROP 1 LASTPIN (4475 5350) $PN 1
J 0
(4485 5330);
DISPLAY 0.489362 (4485 5330);
PAINT MONO (4485 5330);
FORCEPROP 1 LASTPIN (4475 5150) $PN 2
J 0
(4485 5130);
DISPLAY 0.489362 (4485 5130);
PAINT MONO (4485 5130);
FORCEPROP 1 LAST MATERIAL X7R
J 0
(4525 5150);
DISPLAY 0.489362 (4525 5150);
PAINT SKYBLUE (4525 5150);
FORCEPROP 1 LAST TOLERANCE 10%
J 0
(4525 5200);
DISPLAY 0.489362 (4525 5200);
PAINT SKYBLUE (4525 5200);
FORCEPROP 1 LAST VALUE 0.1UF
J 0
(4525 5300);
DISPLAY 0.489362 (4525 5300);
PAINT SKYBLUE (4525 5300);
FORCEPROP 1 LAST VOLTAGE 25V
J 0
(4525 5250);
DISPLAY 0.489362 (4525 5250);
PAINT SKYBLUE (4525 5250);
FORCEPROP 1 LAST PACK_TYPE 0402
J 0
(4525 5100);
DISPLAY 0.489362 (4525 5100);
PAINT SKYBLUE (4525 5100);
FORCEPROP 2 LAST CDS_LIB pure_quanta
J 0
(4475 5250);
DISPLAY INVISIBLE (4475 5250);
FORCEPROP 1 LAST PATH I353
J 0
(4525 5400);
DISPLAY 0.978723 (4525 5400);
PAINT WHITE (4525 5400);
DISPLAY INVISIBLE (4525 5400);
FORCEPROP 1 LAST PART_NUMBER CH4104K1B00
J 0
(4525 5100);
DISPLAY 0.978723 (4525 5100);
PAINT SKYBLUE (4525 5100);
DISPLAY INVISIBLE (4525 5100);
FORCEADD Q_CAP..1
(4675 5250);
FORCEPROP 1 LAST LOCATION C1219
J 0
(4725 5350);
DISPLAY 0.489362 (4725 5350);
PAINT SKYBLUE (4725 5350);
FORCEPROP 0 LAST $SEC 1
J 0
(4725 5400);
DISPLAY 0.680851 (4725 5400);
PAINT MONO (4725 5400);
DISPLAY INVISIBLE (4725 5400);
FORCEPROP 0 LAST CDS_SEC 1
J 0
(4725 5400);
DISPLAY 1.021277 (4725 5400);
DISPLAY INVISIBLE (4725 5400);
FORCEPROP 1 LASTPIN (4675 5350) $PN 1
J 0
(4685 5330);
DISPLAY 0.489362 (4685 5330);
PAINT MONO (4685 5330);
FORCEPROP 1 LASTPIN (4675 5150) $PN 2
J 0
(4685 5130);
DISPLAY 0.489362 (4685 5130);
PAINT MONO (4685 5130);
FORCEPROP 1 LAST MATERIAL X7R
J 0
(4725 5150);
DISPLAY 0.489362 (4725 5150);
PAINT SKYBLUE (4725 5150);
FORCEPROP 1 LAST TOLERANCE 10%
J 0
(4725 5200);
DISPLAY 0.489362 (4725 5200);
PAINT SKYBLUE (4725 5200);
FORCEPROP 1 LAST VALUE 0.1UF
J 0
(4725 5300);
DISPLAY 0.489362 (4725 5300);
PAINT SKYBLUE (4725 5300);
FORCEPROP 1 LAST VOLTAGE 25V
J 0
(4725 5250);
DISPLAY 0.489362 (4725 5250);
PAINT SKYBLUE (4725 5250);
FORCEPROP 1 LAST PACK_TYPE 0402
J 0
(4725 5100);
DISPLAY 0.489362 (4725 5100);
PAINT SKYBLUE (4725 5100);
FORCEPROP 2 LAST CDS_LIB pure_quanta
J 0
(4675 5250);
DISPLAY INVISIBLE (4675 5250);
FORCEPROP 1 LAST PATH I354
J 0
(4725 5400);
DISPLAY 0.978723 (4725 5400);
PAINT WHITE (4725 5400);
DISPLAY INVISIBLE (4725 5400);
FORCEPROP 1 LAST PART_NUMBER CH4104K1B00
J 0
(4725 5100);
DISPLAY 0.978723 (4725 5100);
PAINT SKYBLUE (4725 5100);
DISPLAY INVISIBLE (4725 5100);
FORCEADD VCC_CORE..1
(4675 5600);
FORCEPROP 3 LASTPIN (4675 5550) SIG_NAME P3V3_9ZX_VDDA_0\g
J 0
(4685 5560);
DISPLAY 0.659574 (4685 5560);
PAINT MONO (4685 5560);
DISPLAY INVISIBLE (4685 5560);
FORCEPROP 1 LAST HDL_POWER P3V3_9ZX_VDDA_0
J 1
(4675 5650);
DISPLAY 0.489362 (4675 5650);
PAINT GREEN (4675 5650);
FORCEPROP 2 LAST BOM_COST SYS_CLOCK
J 0
(4675 5750);
DISPLAY 0.808511 (4675 5750);
DISPLAY INVISIBLE (4675 5750);
FORCEPROP 2 LAST CDS_LIB pure_quanta_power
J 0
(4675 5600);
DISPLAY INVISIBLE (4675 5600);
FORCEPROP 1 LAST PATH I355
J 0
(4725 5625);
DISPLAY 0.872340 (4725 5625);
PAINT AQUA (4725 5625);
DISPLAY INVISIBLE (4725 5625);
FORCEPROP 0 LAST VOLTAGE 3.3
J 0
(4675 5750);
DISPLAY 1.021277 (4675 5750);
PAINT SKYBLUE (4675 5750);
DISPLAY INVISIBLE (4675 5750);
FORCEPROP 2 LAST ROOM DB2000_1_BCLK
J 0
(4675 5700);
DISPLAY 0.808511 (4675 5700);
PAINT RED (4675 5700);
DISPLAY INVISIBLE (4675 5700);
FORCEADD UNIVERSAL_GND..1
(2325 950);
FORCEPROP 3 LASTPIN (2325 1000) SIG_NAME GND\g
J 0
(2335 1010);
DISPLAY 0.659574 (2335 1010);
PAINT MONO (2335 1010);
DISPLAY INVISIBLE (2335 1010);
FORCEPROP 1 LAST HDL_POWER GND
J 1
(2350 875);
DISPLAY 0.489362 (2350 875);
PAINT GREEN (2350 875);
FORCEPROP 2 LAST CDS_LIB pure_quanta_power
J 0
(2325 950);
DISPLAY INVISIBLE (2325 950);
FORCEPROP 1 LAST PATH I356
J 0
(2400 950);
DISPLAY 0.872340 (2400 950);
PAINT AQUA (2400 950);
DISPLAY INVISIBLE (2400 950);
FORCEADD Q_CAP..1
(2325 1235);
FORCEPROP 1 LAST LOCATION C1194
J 0
(2375 1335);
DISPLAY 0.489362 (2375 1335);
PAINT SKYBLUE (2375 1335);
FORCEPROP 0 LAST $SEC 1
J 0
(2375 1400);
DISPLAY 0.680851 (2375 1400);
PAINT MONO (2375 1400);
DISPLAY INVISIBLE (2375 1400);
FORCEPROP 0 LAST CDS_SEC 1
J 0
(2375 1400);
DISPLAY 1.021277 (2375 1400);
DISPLAY INVISIBLE (2375 1400);
FORCEPROP 1 LASTPIN (2325 1335) $PN 1
J 0
(2335 1315);
DISPLAY 0.489362 (2335 1315);
PAINT MONO (2335 1315);
FORCEPROP 1 LASTPIN (2325 1135) $PN 2
J 0
(2335 1115);
DISPLAY 0.489362 (2335 1115);
PAINT MONO (2335 1115);
FORCEPROP 1 LAST MATERIAL X6S
J 0
(2375 1135);
DISPLAY 0.489362 (2375 1135);
PAINT SKYBLUE (2375 1135);
FORCEPROP 1 LAST TOLERANCE 10%
J 0
(2375 1185);
DISPLAY 0.489362 (2375 1185);
PAINT SKYBLUE (2375 1185);
FORCEPROP 1 LAST VALUE 1UF
J 0
(2375 1285);
DISPLAY 0.489362 (2375 1285);
PAINT SKYBLUE (2375 1285);
FORCEPROP 1 LAST VOLTAGE 25V
J 0
(2375 1235);
DISPLAY 0.489362 (2375 1235);
PAINT SKYBLUE (2375 1235);
FORCEPROP 1 LAST PACK_TYPE C0402
J 0
(2375 1085);
DISPLAY 0.489362 (2375 1085);
PAINT SKYBLUE (2375 1085);
FORCEPROP 2 LAST CDS_LIB pure_quanta
J 0
(2325 1235);
DISPLAY INVISIBLE (2325 1235);
FORCEPROP 1 LAST PATH I357
J 0
(2375 1385);
DISPLAY 0.978723 (2375 1385);
PAINT WHITE (2375 1385);
DISPLAY INVISIBLE (2375 1385);
FORCEPROP 1 LAST PART_NUMBER CH5104KEB02
J 0
(2375 1085);
DISPLAY 0.617021 (2375 1085);
PAINT SKYBLUE (2375 1085);
DISPLAY INVISIBLE (2375 1085);
FORCEADD UNIVERSAL_GND..1
(2725 925);
FORCEPROP 3 LASTPIN (2725 975) SIG_NAME GND\g
J 0
(2735 985);
DISPLAY 0.659574 (2735 985);
PAINT MONO (2735 985);
DISPLAY INVISIBLE (2735 985);
FORCEPROP 1 LAST HDL_POWER GND
J 1
(2750 850);
DISPLAY 0.489362 (2750 850);
PAINT GREEN (2750 850);
FORCEPROP 2 LAST CDS_LIB pure_quanta_power
J 0
(2725 925);
DISPLAY INVISIBLE (2725 925);
FORCEPROP 1 LAST PATH I359
J 0
(2800 925);
DISPLAY 0.872340 (2800 925);
PAINT AQUA (2800 925);
DISPLAY INVISIBLE (2800 925);
FORCEADD UNIVERSAL_GND..1
(2975 925);
FORCEPROP 3 LASTPIN (2975 975) SIG_NAME GND\g
J 0
(2985 985);
DISPLAY 0.659574 (2985 985);
PAINT MONO (2985 985);
DISPLAY INVISIBLE (2985 985);
FORCEPROP 1 LAST HDL_POWER GND
J 1
(3000 850);
DISPLAY 0.489362 (3000 850);
PAINT GREEN (3000 850);
FORCEPROP 2 LAST CDS_LIB pure_quanta_power
J 0
(2975 925);
DISPLAY INVISIBLE (2975 925);
FORCEPROP 1 LAST PATH I360
J 0
(3050 925);
DISPLAY 0.872340 (3050 925);
PAINT AQUA (3050 925);
DISPLAY INVISIBLE (3050 925);
FORCEADD Q_CAP..1
(2725 1200);
FORCEPROP 1 LAST LOCATION C1200
J 0
(2775 1300);
DISPLAY 0.489362 (2775 1300);
PAINT SKYBLUE (2775 1300);
FORCEPROP 0 LAST $SEC 1
J 0
(2775 1350);
DISPLAY 0.680851 (2775 1350);
PAINT MONO (2775 1350);
DISPLAY INVISIBLE (2775 1350);
FORCEPROP 0 LAST CDS_SEC 1
J 0
(2775 1350);
DISPLAY 1.021277 (2775 1350);
DISPLAY INVISIBLE (2775 1350);
FORCEPROP 1 LASTPIN (2725 1300) $PN 1
J 0
(2735 1280);
DISPLAY 0.489362 (2735 1280);
PAINT MONO (2735 1280);
FORCEPROP 1 LASTPIN (2725 1100) $PN 2
J 0
(2735 1080);
DISPLAY 0.489362 (2735 1080);
PAINT MONO (2735 1080);
FORCEPROP 1 LAST MATERIAL X7R
J 0
(2775 1100);
DISPLAY 0.489362 (2775 1100);
PAINT SKYBLUE (2775 1100);
FORCEPROP 1 LAST TOLERANCE 10%
J 0
(2775 1150);
DISPLAY 0.489362 (2775 1150);
PAINT SKYBLUE (2775 1150);
FORCEPROP 1 LAST VALUE 0.1UF
J 0
(2775 1250);
DISPLAY 0.489362 (2775 1250);
PAINT SKYBLUE (2775 1250);
FORCEPROP 1 LAST VOLTAGE 25V
J 0
(2775 1200);
DISPLAY 0.489362 (2775 1200);
PAINT SKYBLUE (2775 1200);
FORCEPROP 1 LAST PACK_TYPE 0402
J 0
(2775 1050);
DISPLAY 0.489362 (2775 1050);
PAINT SKYBLUE (2775 1050);
FORCEPROP 2 LAST CDS_LIB pure_quanta
J 0
(2725 1200);
DISPLAY INVISIBLE (2725 1200);
FORCEPROP 1 LAST PATH I361
J 0
(2775 1350);
DISPLAY 0.978723 (2775 1350);
PAINT WHITE (2775 1350);
DISPLAY INVISIBLE (2775 1350);
FORCEPROP 1 LAST PART_NUMBER CH4104K1B00
J 0
(2775 1050);
DISPLAY 0.978723 (2775 1050);
PAINT SKYBLUE (2775 1050);
DISPLAY INVISIBLE (2775 1050);
FORCEADD Q_CAP..1
(2975 1200);
FORCEPROP 1 LAST LOCATION C1204
J 0
(3025 1300);
DISPLAY 0.489362 (3025 1300);
PAINT SKYBLUE (3025 1300);
FORCEPROP 0 LAST $SEC 1
J 0
(3025 1350);
DISPLAY 0.680851 (3025 1350);
PAINT MONO (3025 1350);
DISPLAY INVISIBLE (3025 1350);
FORCEPROP 0 LAST CDS_SEC 1
J 0
(3025 1350);
DISPLAY 1.021277 (3025 1350);
DISPLAY INVISIBLE (3025 1350);
FORCEPROP 1 LASTPIN (2975 1300) $PN 1
J 0
(2985 1280);
DISPLAY 0.489362 (2985 1280);
PAINT MONO (2985 1280);
FORCEPROP 1 LASTPIN (2975 1100) $PN 2
J 0
(2985 1080);
DISPLAY 0.489362 (2985 1080);
PAINT MONO (2985 1080);
FORCEPROP 1 LAST MATERIAL X7R
J 0
(3025 1100);
DISPLAY 0.489362 (3025 1100);
PAINT SKYBLUE (3025 1100);
FORCEPROP 1 LAST TOLERANCE 10%
J 0
(3025 1150);
DISPLAY 0.489362 (3025 1150);
PAINT SKYBLUE (3025 1150);
FORCEPROP 1 LAST VALUE 0.1UF
J 0
(3025 1250);
DISPLAY 0.489362 (3025 1250);
PAINT SKYBLUE (3025 1250);
FORCEPROP 1 LAST VOLTAGE 25V
J 0
(3025 1200);
DISPLAY 0.489362 (3025 1200);
PAINT SKYBLUE (3025 1200);
FORCEPROP 1 LAST PACK_TYPE 0402
J 0
(3025 1050);
DISPLAY 0.489362 (3025 1050);
PAINT SKYBLUE (3025 1050);
FORCEPROP 2 LAST CDS_LIB pure_quanta
J 0
(2975 1200);
DISPLAY INVISIBLE (2975 1200);
FORCEPROP 1 LAST PATH I363
J 0
(3025 1350);
DISPLAY 0.978723 (3025 1350);
PAINT WHITE (3025 1350);
DISPLAY INVISIBLE (3025 1350);
FORCEPROP 1 LAST PART_NUMBER CH4104K1B00
J 0
(3025 1050);
DISPLAY 0.978723 (3025 1050);
PAINT SKYBLUE (3025 1050);
DISPLAY INVISIBLE (3025 1050);
FORCEADD UNIVERSAL_GND..1
(3200 925);
FORCEPROP 3 LASTPIN (3200 975) SIG_NAME GND\g
J 0
(3210 985);
DISPLAY 0.659574 (3210 985);
PAINT MONO (3210 985);
DISPLAY INVISIBLE (3210 985);
FORCEPROP 1 LAST HDL_POWER GND
J 1
(3225 850);
DISPLAY 0.489362 (3225 850);
PAINT GREEN (3225 850);
FORCEPROP 2 LAST CDS_LIB pure_quanta_power
J 0
(3200 925);
DISPLAY INVISIBLE (3200 925);
FORCEPROP 1 LAST PATH I365
J 0
(3275 925);
DISPLAY 0.872340 (3275 925);
PAINT AQUA (3275 925);
DISPLAY INVISIBLE (3275 925);
FORCEADD UNIVERSAL_GND..1
(3430 920);
FORCEPROP 3 LASTPIN (3430 970) SIG_NAME GND\g
J 0
(3440 980);
DISPLAY 0.659574 (3440 980);
PAINT MONO (3440 980);
DISPLAY INVISIBLE (3440 980);
FORCEPROP 1 LAST HDL_POWER GND
J 1
(3455 845);
DISPLAY 0.489362 (3455 845);
PAINT GREEN (3455 845);
FORCEPROP 2 LAST CDS_LIB pure_quanta_power
J 0
(3430 920);
DISPLAY INVISIBLE (3430 920);
FORCEPROP 1 LAST PATH I366
J 0
(3505 920);
DISPLAY 0.872340 (3505 920);
PAINT AQUA (3505 920);
DISPLAY INVISIBLE (3505 920);
FORCEADD Q_CAP..1
(3200 1200);
FORCEPROP 1 LAST LOCATION C1208
J 0
(3250 1300);
DISPLAY 0.489362 (3250 1300);
PAINT SKYBLUE (3250 1300);
FORCEPROP 0 LAST $SEC 1
J 0
(3250 1350);
DISPLAY 0.680851 (3250 1350);
PAINT MONO (3250 1350);
DISPLAY INVISIBLE (3250 1350);
FORCEPROP 0 LAST CDS_SEC 1
J 0
(3250 1350);
DISPLAY 1.021277 (3250 1350);
DISPLAY INVISIBLE (3250 1350);
FORCEPROP 1 LASTPIN (3200 1300) $PN 1
J 0
(3210 1280);
DISPLAY 0.489362 (3210 1280);
PAINT MONO (3210 1280);
FORCEPROP 1 LASTPIN (3200 1100) $PN 2
J 0
(3210 1080);
DISPLAY 0.489362 (3210 1080);
PAINT MONO (3210 1080);
FORCEPROP 1 LAST MATERIAL X7R
J 0
(3250 1100);
DISPLAY 0.489362 (3250 1100);
PAINT SKYBLUE (3250 1100);
FORCEPROP 1 LAST TOLERANCE 10%
J 0
(3250 1150);
DISPLAY 0.489362 (3250 1150);
PAINT SKYBLUE (3250 1150);
FORCEPROP 1 LAST VALUE 0.1UF
J 0
(3250 1250);
DISPLAY 0.489362 (3250 1250);
PAINT SKYBLUE (3250 1250);
FORCEPROP 1 LAST VOLTAGE 25V
J 0
(3250 1200);
DISPLAY 0.489362 (3250 1200);
PAINT SKYBLUE (3250 1200);
FORCEPROP 1 LAST PACK_TYPE 0402
J 0
(3250 1050);
DISPLAY 0.489362 (3250 1050);
PAINT SKYBLUE (3250 1050);
FORCEPROP 2 LAST CDS_LIB pure_quanta
J 0
(3200 1200);
DISPLAY INVISIBLE (3200 1200);
FORCEPROP 1 LAST PATH I367
J 0
(3250 1350);
DISPLAY 0.978723 (3250 1350);
PAINT WHITE (3250 1350);
DISPLAY INVISIBLE (3250 1350);
FORCEPROP 1 LAST PART_NUMBER CH4104K1B00
J 0
(3250 1050);
DISPLAY 0.978723 (3250 1050);
PAINT SKYBLUE (3250 1050);
DISPLAY INVISIBLE (3250 1050);
FORCEADD Q_CAP..1
(3430 1195);
FORCEPROP 1 LAST LOCATION C1210
J 0
(3480 1295);
DISPLAY 0.489362 (3480 1295);
PAINT SKYBLUE (3480 1295);
FORCEPROP 0 LAST $SEC 1
J 0
(3500 1350);
DISPLAY 0.680851 (3500 1350);
PAINT MONO (3500 1350);
DISPLAY INVISIBLE (3500 1350);
FORCEPROP 0 LAST CDS_SEC 1
J 0
(3500 1350);
DISPLAY 1.021277 (3500 1350);
DISPLAY INVISIBLE (3500 1350);
FORCEPROP 1 LASTPIN (3430 1295) $PN 1
J 0
(3440 1275);
DISPLAY 0.489362 (3440 1275);
PAINT MONO (3440 1275);
FORCEPROP 1 LASTPIN (3430 1095) $PN 2
J 0
(3440 1075);
DISPLAY 0.489362 (3440 1075);
PAINT MONO (3440 1075);
FORCEPROP 1 LAST MATERIAL X7R
J 0
(3480 1095);
DISPLAY 0.489362 (3480 1095);
PAINT SKYBLUE (3480 1095);
FORCEPROP 1 LAST TOLERANCE 10%
J 0
(3480 1145);
DISPLAY 0.489362 (3480 1145);
PAINT SKYBLUE (3480 1145);
FORCEPROP 1 LAST VALUE 0.1UF
J 0
(3480 1245);
DISPLAY 0.489362 (3480 1245);
PAINT SKYBLUE (3480 1245);
FORCEPROP 1 LAST VOLTAGE 25V
J 0
(3480 1195);
DISPLAY 0.489362 (3480 1195);
PAINT SKYBLUE (3480 1195);
FORCEPROP 1 LAST PACK_TYPE 0402
J 0
(3480 1045);
DISPLAY 0.489362 (3480 1045);
PAINT SKYBLUE (3480 1045);
FORCEPROP 2 LAST CDS_LIB pure_quanta
J 0
(3430 1195);
DISPLAY INVISIBLE (3430 1195);
FORCEPROP 1 LAST PATH I369
J 0
(3480 1345);
DISPLAY 0.978723 (3480 1345);
PAINT WHITE (3480 1345);
DISPLAY INVISIBLE (3480 1345);
FORCEPROP 1 LAST PART_NUMBER CH4104K1B00
J 0
(3480 1045);
DISPLAY 0.978723 (3480 1045);
PAINT SKYBLUE (3480 1045);
DISPLAY INVISIBLE (3480 1045);
FORCEADD Q_INDUCTOR..1
(2150 1900);
FORCEPROP 1 LAST LOCATION L7
J 0
(2025 2060);
DISPLAY 0.489362 (2025 2060);
PAINT SKYBLUE (2025 2060);
FORCEPROP 0 LAST $SEC 1
J 0
(2025 2175);
DISPLAY 0.680851 (2025 2175);
PAINT MONO (2025 2175);
DISPLAY INVISIBLE (2025 2175);
FORCEPROP 0 LAST CDS_SEC 1
J 0
(2025 2175);
DISPLAY 1.021277 (2025 2175);
DISPLAY INVISIBLE (2025 2175);
FORCEPROP 0 LASTPIN (2050 1875) $PN 1
J 2
(2040 1885);
DISPLAY 0.489362 (2040 1885);
PAINT MONO (2040 1885);
FORCEPROP 0 LASTPIN (2250 1875) $PN 2
J 0
(2260 1885);
DISPLAY 0.489362 (2260 1885);
PAINT MONO (2260 1885);
FORCEPROP 1 LAST MATERIAL IND
J 0
(2025 1955);
DISPLAY 0.489362 (2025 1955);
PAINT SKYBLUE (2025 1955);
FORCEPROP 2 LAST VALUE 330/2.5A
J 0
(2025 2100);
DISPLAY 0.489362 (2025 2100);
PAINT SKYBLUE (2025 2100);
FORCEPROP 1 LAST PART_NUMBER CX12S331000
J 0
(2025 2010);
DISPLAY 0.489362 (2025 2010);
PAINT SKYBLUE (2025 2010);
FORCEPROP 2 LAST PACK_TYPE SMLF
J 0
(2025 2150);
DISPLAY 0.489362 (2025 2150);
PAINT SKYBLUE (2025 2150);
FORCEPROP 1 LAST NEEDS_NO_SIZE TRUE
J 0
(2150 1900);
DISPLAY 0.468085 (2150 1900);
PAINT GREEN (2150 1900);
DISPLAY INVISIBLE (2150 1900);
FORCEPROP 2 LAST CDS_LIB pure_quanta
J 0
(2150 1900);
DISPLAY INVISIBLE (2150 1900);
FORCEPROP 1 LAST PATH I370
J 0
(2225 1955);
DISPLAY 0.723404 (2225 1955);
PAINT GREEN (2225 1955);
DISPLAY INVISIBLE (2225 1955);
FORCEADD UNIVERSAL_POWER..1
(1800 2025);
FORCEPROP 3 LASTPIN (1800 1975) SIG_NAME P3V3\g
J 0
(1810 1985);
DISPLAY 0.659574 (1810 1985);
PAINT MONO (1810 1985);
DISPLAY INVISIBLE (1810 1985);
FORCEPROP 1 LAST HDL_POWER P3V3
J 1
(1800 2075);
DISPLAY 0.489362 (1800 2075);
PAINT GREEN (1800 2075);
FORCEPROP 2 LAST CDS_LIB pure_quanta_power
J 0
(1800 2025);
DISPLAY INVISIBLE (1800 2025);
FORCEPROP 1 LAST PATH I371
J 0
(1850 2050);
DISPLAY 0.872340 (1850 2050);
PAINT AQUA (1850 2050);
DISPLAY INVISIBLE (1850 2050);
FORCEADD UNIVERSAL_POWER..1
(3475 2075);
FORCEPROP 3 LASTPIN (3475 2025) SIG_NAME P3V3_9ZX_VDD_1\g
J 0
(3485 2035);
DISPLAY 0.659574 (3485 2035);
PAINT MONO (3485 2035);
DISPLAY INVISIBLE (3485 2035);
FORCEPROP 1 LAST HDL_POWER P3V3_9ZX_VDD_1
J 1
(3475 2125);
DISPLAY 0.489362 (3475 2125);
PAINT GREEN (3475 2125);
FORCEPROP 2 LAST CDS_LIB pure_quanta_power
J 0
(3475 2075);
DISPLAY INVISIBLE (3475 2075);
FORCEPROP 2 LAST BOM_COST SYS_CLOCK
J 0
(3475 2225);
DISPLAY 0.808511 (3475 2225);
DISPLAY INVISIBLE (3475 2225);
FORCEPROP 1 LAST PATH I376
J 0
(3525 2100);
DISPLAY 0.872340 (3525 2100);
PAINT AQUA (3525 2100);
DISPLAY INVISIBLE (3525 2100);
FORCEPROP 0 LAST VOLTAGE 3.3
J 0
(3475 2225);
DISPLAY 1.021277 (3475 2225);
PAINT SKYBLUE (3475 2225);
DISPLAY INVISIBLE (3475 2225);
FORCEPROP 2 LAST ROOM DB2000_1_BCLK
J 0
(3475 2175);
DISPLAY 0.808511 (3475 2175);
PAINT RED (3475 2175);
DISPLAY INVISIBLE (3475 2175);
FORCEADD UNIVERSAL_GND..1
(3660 915);
FORCEPROP 3 LASTPIN (3660 965) SIG_NAME GND\g
J 0
(3670 975);
DISPLAY 0.659574 (3670 975);
PAINT MONO (3670 975);
DISPLAY INVISIBLE (3670 975);
FORCEPROP 1 LAST HDL_POWER GND
J 1
(3685 840);
DISPLAY 0.489362 (3685 840);
PAINT GREEN (3685 840);
FORCEPROP 2 LAST CDS_LIB pure_quanta_power
J 0
(3660 915);
DISPLAY INVISIBLE (3660 915);
FORCEPROP 1 LAST PATH I377
J 0
(3735 915);
DISPLAY 0.872340 (3735 915);
PAINT AQUA (3735 915);
DISPLAY INVISIBLE (3735 915);
FORCEADD Q_CAP..1
(3660 1190);
FORCEPROP 1 LAST LOCATION C1212
J 0
(3710 1290);
DISPLAY 0.489362 (3710 1290);
PAINT SKYBLUE (3710 1290);
FORCEPROP 0 LAST $SEC 1
J 0
(3725 1350);
DISPLAY 0.680851 (3725 1350);
PAINT MONO (3725 1350);
DISPLAY INVISIBLE (3725 1350);
FORCEPROP 0 LAST CDS_SEC 1
J 0
(3725 1350);
DISPLAY 1.021277 (3725 1350);
DISPLAY INVISIBLE (3725 1350);
FORCEPROP 1 LASTPIN (3660 1290) $PN 1
J 0
(3670 1270);
DISPLAY 0.489362 (3670 1270);
PAINT MONO (3670 1270);
FORCEPROP 1 LASTPIN (3660 1090) $PN 2
J 0
(3670 1070);
DISPLAY 0.489362 (3670 1070);
PAINT MONO (3670 1070);
FORCEPROP 1 LAST MATERIAL X7R
J 0
(3710 1090);
DISPLAY 0.489362 (3710 1090);
PAINT SKYBLUE (3710 1090);
FORCEPROP 1 LAST TOLERANCE 10%
J 0
(3710 1140);
DISPLAY 0.489362 (3710 1140);
PAINT SKYBLUE (3710 1140);
FORCEPROP 1 LAST VALUE 0.1UF
J 0
(3710 1240);
DISPLAY 0.489362 (3710 1240);
PAINT SKYBLUE (3710 1240);
FORCEPROP 1 LAST VOLTAGE 25V
J 0
(3710 1190);
DISPLAY 0.489362 (3710 1190);
PAINT SKYBLUE (3710 1190);
FORCEPROP 1 LAST PACK_TYPE 0402
J 0
(3710 1040);
DISPLAY 0.489362 (3710 1040);
PAINT SKYBLUE (3710 1040);
FORCEPROP 2 LAST CDS_LIB pure_quanta
J 0
(3660 1190);
DISPLAY INVISIBLE (3660 1190);
FORCEPROP 1 LAST PATH I379
J 0
(3710 1340);
DISPLAY 0.978723 (3710 1340);
PAINT WHITE (3710 1340);
DISPLAY INVISIBLE (3710 1340);
FORCEPROP 1 LAST PART_NUMBER CH4104K1B00
J 0
(3710 1040);
DISPLAY 0.978723 (3710 1040);
PAINT SKYBLUE (3710 1040);
DISPLAY INVISIBLE (3710 1040);
FORCEADD UNIVERSAL_GND..1
(4275 1450);
FORCEPROP 3 LASTPIN (4275 1500) SIG_NAME GND\g
J 0
(4285 1510);
DISPLAY 0.659574 (4285 1510);
PAINT MONO (4285 1510);
DISPLAY INVISIBLE (4285 1510);
FORCEPROP 1 LAST HDL_POWER GND
J 1
(4300 1375);
DISPLAY 0.489362 (4300 1375);
PAINT GREEN (4300 1375);
FORCEPROP 2 LAST CDS_LIB pure_quanta_power
J 0
(4275 1450);
DISPLAY INVISIBLE (4275 1450);
FORCEPROP 1 LAST PATH I381
J 0
(4350 1450);
DISPLAY 0.872340 (4350 1450);
PAINT AQUA (4350 1450);
DISPLAY INVISIBLE (4350 1450);
FORCEADD UNIVERSAL_GND..1
(4525 1450);
FORCEPROP 3 LASTPIN (4525 1500) SIG_NAME GND\g
J 0
(4535 1510);
DISPLAY 0.659574 (4535 1510);
PAINT MONO (4535 1510);
DISPLAY INVISIBLE (4535 1510);
FORCEPROP 1 LAST HDL_POWER GND
J 1
(4550 1375);
DISPLAY 0.489362 (4550 1375);
PAINT GREEN (4550 1375);
FORCEPROP 2 LAST CDS_LIB pure_quanta_power
J 0
(4525 1450);
DISPLAY INVISIBLE (4525 1450);
FORCEPROP 1 LAST PATH I382
J 0
(4600 1450);
DISPLAY 0.872340 (4600 1450);
PAINT AQUA (4600 1450);
DISPLAY INVISIBLE (4600 1450);
FORCEADD UNIVERSAL_GND..1
(4725 1450);
FORCEPROP 3 LASTPIN (4725 1500) SIG_NAME GND\g
J 0
(4735 1510);
DISPLAY 0.659574 (4735 1510);
PAINT MONO (4735 1510);
DISPLAY INVISIBLE (4735 1510);
FORCEPROP 1 LAST HDL_POWER GND
J 1
(4750 1375);
DISPLAY 0.489362 (4750 1375);
PAINT GREEN (4750 1375);
FORCEPROP 2 LAST CDS_LIB pure_quanta_power
J 0
(4725 1450);
DISPLAY INVISIBLE (4725 1450);
FORCEPROP 1 LAST PATH I383
J 0
(4800 1450);
DISPLAY 0.872340 (4800 1450);
PAINT AQUA (4800 1450);
DISPLAY INVISIBLE (4800 1450);
FORCEADD Q_RES..1
(3825 1875);
FORCEPROP 1 LAST LOCATION R795
J 0
(3775 1925);
DISPLAY 0.489362 (3775 1925);
PAINT SKYBLUE (3775 1925);
FORCEPROP 0 LAST $SEC 1
J 0
(3775 1975);
DISPLAY 0.680851 (3775 1975);
PAINT MONO (3775 1975);
DISPLAY INVISIBLE (3775 1975);
FORCEPROP 0 LAST CDS_SEC 1
J 0
(3775 1975);
DISPLAY 1.021277 (3775 1975);
DISPLAY INVISIBLE (3775 1975);
FORCEPROP 1 LASTPIN (3725 1875) $PN 1
J 0
(3737 1887);
DISPLAY 0.489362 (3737 1887);
PAINT MONO (3737 1887);
FORCEPROP 1 LASTPIN (3925 1875) $PN 2
J 0
(3887 1887);
DISPLAY 0.489362 (3887 1887);
PAINT MONO (3887 1887);
FORCEPROP 1 LAST WATTAGE 1/10W
J 2
(3825 1800);
DISPLAY 0.489362 (3825 1800);
PAINT SKYBLUE (3825 1800);
FORCEPROP 1 LAST MATERIAL CHIP
J 0
(3850 1775);
DISPLAY 0.489362 (3850 1775);
PAINT SKYBLUE (3850 1775);
FORCEPROP 1 LAST TOLERANCE 1%
J 0
(3950 1925);
DISPLAY 0.489362 (3950 1925);
PAINT SKYBLUE (3950 1925);
FORCEPROP 1 LAST VALUE 1
J 2
(3750 1900);
DISPLAY 0.489362 (3750 1900);
PAINT SKYBLUE (3750 1900);
FORCEPROP 1 LAST PACK_TYPE 0603LF
J 0
(3975 1825);
DISPLAY 0.489362 (3975 1825);
PAINT SKYBLUE (3975 1825);
FORCEPROP 2 LAST CDS_LIB pure_quanta
J 0
(3825 1875);
DISPLAY INVISIBLE (3825 1875);
FORCEPROP 1 LAST PATH I384
J 0
(3775 2025);
DISPLAY 0.978723 (3775 2025);
PAINT WHITE (3775 2025);
DISPLAY INVISIBLE (3775 2025);
FORCEPROP 1 LAST PART_NUMBER CS-1003F920
J 0
(3775 1975);
DISPLAY 0.978723 (3775 1975);
PAINT SKYBLUE (3775 1975);
DISPLAY INVISIBLE (3775 1975);
FORCEADD Q_CAP..1
(4275 1725);
FORCEPROP 1 LAST LOCATION C1216
J 0
(4325 1825);
DISPLAY 0.489362 (4325 1825);
PAINT SKYBLUE (4325 1825);
FORCEPROP 0 LAST $SEC 1
J 0
(4325 1875);
DISPLAY 0.680851 (4325 1875);
PAINT MONO (4325 1875);
DISPLAY INVISIBLE (4325 1875);
FORCEPROP 0 LAST CDS_SEC 1
J 0
(4325 1875);
DISPLAY 1.021277 (4325 1875);
DISPLAY INVISIBLE (4325 1875);
FORCEPROP 1 LASTPIN (4275 1825) $PN 1
J 0
(4285 1805);
DISPLAY 0.489362 (4285 1805);
PAINT MONO (4285 1805);
FORCEPROP 1 LASTPIN (4275 1625) $PN 2
J 0
(4285 1605);
DISPLAY 0.489362 (4285 1605);
PAINT MONO (4285 1605);
FORCEPROP 1 LAST MATERIAL X6S
J 0
(4325 1625);
DISPLAY 0.489362 (4325 1625);
PAINT SKYBLUE (4325 1625);
FORCEPROP 1 LAST TOLERANCE 10%
J 0
(4325 1675);
DISPLAY 0.489362 (4325 1675);
PAINT SKYBLUE (4325 1675);
FORCEPROP 1 LAST VALUE 1UF
J 0
(4325 1775);
DISPLAY 0.489362 (4325 1775);
PAINT SKYBLUE (4325 1775);
FORCEPROP 1 LAST VOLTAGE 25V
J 0
(4325 1725);
DISPLAY 0.489362 (4325 1725);
PAINT SKYBLUE (4325 1725);
FORCEPROP 1 LAST PACK_TYPE C0402
J 0
(4325 1575);
DISPLAY 0.489362 (4325 1575);
PAINT SKYBLUE (4325 1575);
FORCEPROP 2 LAST CDS_LIB pure_quanta
J 0
(4275 1725);
DISPLAY INVISIBLE (4275 1725);
FORCEPROP 1 LAST PATH I385
J 0
(4325 1875);
DISPLAY 0.978723 (4325 1875);
PAINT WHITE (4325 1875);
DISPLAY INVISIBLE (4325 1875);
FORCEPROP 1 LAST PART_NUMBER CH5104KEB02
J 0
(4325 1575);
DISPLAY 0.617021 (4325 1575);
PAINT SKYBLUE (4325 1575);
DISPLAY INVISIBLE (4325 1575);
FORCEADD Q_CAP..1
(4525 1725);
FORCEPROP 1 LAST LOCATION C1218
J 0
(4575 1825);
DISPLAY 0.489362 (4575 1825);
PAINT SKYBLUE (4575 1825);
FORCEPROP 0 LAST $SEC 1
J 0
(4575 1875);
DISPLAY 0.680851 (4575 1875);
PAINT MONO (4575 1875);
DISPLAY INVISIBLE (4575 1875);
FORCEPROP 0 LAST CDS_SEC 1
J 0
(4575 1875);
DISPLAY 1.021277 (4575 1875);
DISPLAY INVISIBLE (4575 1875);
FORCEPROP 1 LASTPIN (4525 1825) $PN 1
J 0
(4535 1805);
DISPLAY 0.489362 (4535 1805);
PAINT MONO (4535 1805);
FORCEPROP 1 LASTPIN (4525 1625) $PN 2
J 0
(4535 1605);
DISPLAY 0.489362 (4535 1605);
PAINT MONO (4535 1605);
FORCEPROP 1 LAST MATERIAL X7R
J 0
(4575 1625);
DISPLAY 0.489362 (4575 1625);
PAINT SKYBLUE (4575 1625);
FORCEPROP 1 LAST TOLERANCE 10%
J 0
(4575 1675);
DISPLAY 0.489362 (4575 1675);
PAINT SKYBLUE (4575 1675);
FORCEPROP 1 LAST VALUE 0.1UF
J 0
(4575 1775);
DISPLAY 0.489362 (4575 1775);
PAINT SKYBLUE (4575 1775);
FORCEPROP 1 LAST VOLTAGE 25V
J 0
(4575 1725);
DISPLAY 0.489362 (4575 1725);
PAINT SKYBLUE (4575 1725);
FORCEPROP 1 LAST PACK_TYPE 0402
J 0
(4575 1575);
DISPLAY 0.489362 (4575 1575);
PAINT SKYBLUE (4575 1575);
FORCEPROP 2 LAST CDS_LIB pure_quanta
J 0
(4525 1725);
DISPLAY INVISIBLE (4525 1725);
FORCEPROP 1 LAST PATH I386
J 0
(4575 1875);
DISPLAY 0.978723 (4575 1875);
PAINT WHITE (4575 1875);
DISPLAY INVISIBLE (4575 1875);
FORCEPROP 1 LAST PART_NUMBER CH4104K1B00
J 0
(4575 1575);
DISPLAY 0.978723 (4575 1575);
PAINT SKYBLUE (4575 1575);
DISPLAY INVISIBLE (4575 1575);
FORCEADD Q_CAP..1
(4725 1725);
FORCEPROP 1 LAST LOCATION C1220
J 0
(4775 1825);
DISPLAY 0.489362 (4775 1825);
PAINT SKYBLUE (4775 1825);
FORCEPROP 0 LAST $SEC 1
J 0
(4775 1875);
DISPLAY 0.680851 (4775 1875);
PAINT MONO (4775 1875);
DISPLAY INVISIBLE (4775 1875);
FORCEPROP 0 LAST CDS_SEC 1
J 0
(4775 1875);
DISPLAY 1.021277 (4775 1875);
DISPLAY INVISIBLE (4775 1875);
FORCEPROP 1 LASTPIN (4725 1825) $PN 1
J 0
(4735 1805);
DISPLAY 0.489362 (4735 1805);
PAINT MONO (4735 1805);
FORCEPROP 1 LASTPIN (4725 1625) $PN 2
J 0
(4735 1605);
DISPLAY 0.489362 (4735 1605);
PAINT MONO (4735 1605);
FORCEPROP 1 LAST MATERIAL X7R
J 0
(4775 1625);
DISPLAY 0.489362 (4775 1625);
PAINT SKYBLUE (4775 1625);
FORCEPROP 1 LAST TOLERANCE 10%
J 0
(4775 1675);
DISPLAY 0.489362 (4775 1675);
PAINT SKYBLUE (4775 1675);
FORCEPROP 1 LAST VALUE 0.1UF
J 0
(4775 1775);
DISPLAY 0.489362 (4775 1775);
PAINT SKYBLUE (4775 1775);
FORCEPROP 1 LAST VOLTAGE 25V
J 0
(4775 1725);
DISPLAY 0.489362 (4775 1725);
PAINT SKYBLUE (4775 1725);
FORCEPROP 1 LAST PACK_TYPE 0402
J 0
(4775 1575);
DISPLAY 0.489362 (4775 1575);
PAINT SKYBLUE (4775 1575);
FORCEPROP 2 LAST CDS_LIB pure_quanta
J 0
(4725 1725);
DISPLAY INVISIBLE (4725 1725);
FORCEPROP 1 LAST PATH I387
J 0
(4775 1875);
DISPLAY 0.978723 (4775 1875);
PAINT WHITE (4775 1875);
DISPLAY INVISIBLE (4775 1875);
FORCEPROP 1 LAST PART_NUMBER CH4104K1B00
J 0
(4775 1575);
DISPLAY 0.978723 (4775 1575);
PAINT SKYBLUE (4775 1575);
DISPLAY INVISIBLE (4775 1575);
FORCEADD VCC_CORE..1
(4725 2075);
FORCEPROP 3 LASTPIN (4725 2025) SIG_NAME P3V3_9ZX_VDDA_1\g
J 0
(4735 2035);
DISPLAY 0.659574 (4735 2035);
PAINT MONO (4735 2035);
DISPLAY INVISIBLE (4735 2035);
FORCEPROP 1 LAST HDL_POWER P3V3_9ZX_VDDA_1
J 1
(4725 2125);
DISPLAY 0.489362 (4725 2125);
PAINT GREEN (4725 2125);
FORCEPROP 2 LAST BOM_COST SYS_CLOCK
J 0
(4725 2225);
DISPLAY 0.808511 (4725 2225);
DISPLAY INVISIBLE (4725 2225);
FORCEPROP 2 LAST CDS_LIB pure_quanta_power
J 0
(4725 2075);
DISPLAY INVISIBLE (4725 2075);
FORCEPROP 1 LAST PATH I388
J 0
(4775 2100);
DISPLAY 0.872340 (4775 2100);
PAINT AQUA (4775 2100);
DISPLAY INVISIBLE (4775 2100);
FORCEPROP 0 LAST VOLTAGE 3.3
J 0
(4725 2225);
DISPLAY 1.021277 (4725 2225);
PAINT SKYBLUE (4725 2225);
DISPLAY INVISIBLE (4725 2225);
FORCEPROP 2 LAST ROOM DB2000_1_BCLK
J 0
(4725 2175);
DISPLAY 0.808511 (4725 2175);
PAINT RED (4725 2175);
DISPLAY INVISIBLE (4725 2175);
FORCEADD Q_RES..1
(9450 5325);
FORCEPROP 1 LAST LOCATION R2288
J 0
(9250 5325);
DISPLAY 0.489362 (9250 5325);
PAINT SKYBLUE (9250 5325);
FORCEPROP 0 LAST $SEC 1
J 0
(9375 5375);
DISPLAY 0.680851 (9375 5375);
PAINT MONO (9375 5375);
DISPLAY INVISIBLE (9375 5375);
FORCEPROP 0 LAST CDS_SEC 1
J 0
(9375 5375);
DISPLAY 1.021277 (9375 5375);
DISPLAY INVISIBLE (9375 5375);
FORCEPROP 1 LASTPIN (9350 5325) $PN 1
J 0
(9362 5337);
DISPLAY 0.489362 (9362 5337);
PAINT MONO (9362 5337);
FORCEPROP 1 LASTPIN (9550 5325) $PN 2
J 0
(9512 5337);
DISPLAY 0.489362 (9512 5337);
PAINT MONO (9512 5337);
FORCEPROP 1 LAST VALUE 0
J 2
(9575 5325);
DISPLAY 0.489362 (9575 5325);
PAINT SKYBLUE (9575 5325);
FORCEPROP 2 LAST CDS_LIB pure_quanta
J 0
(9450 5325);
DISPLAY INVISIBLE (9450 5325);
FORCEPROP 1 LAST PATH I399
J 0
(9400 5475);
DISPLAY 0.978723 (9400 5475);
PAINT WHITE (9400 5475);
DISPLAY INVISIBLE (9400 5475);
FORCEPROP 1 LAST WATTAGE 1/16W
J 2
(9850 5250);
DISPLAY 0.489362 (9850 5250);
PAINT SKYBLUE (9850 5250);
DISPLAY INVISIBLE (9850 5250);
FORCEPROP 1 LAST MATERIAL CHIP
J 0
(9875 5250);
DISPLAY 0.489362 (9875 5250);
PAINT SKYBLUE (9875 5250);
DISPLAY INVISIBLE (9875 5250);
FORCEPROP 1 LAST TOLERANCE 5%
J 0
(9425 5250);
DISPLAY 0.489362 (9425 5250);
PAINT SKYBLUE (9425 5250);
DISPLAY INVISIBLE (9425 5250);
FORCEPROP 1 LAST PART_NUMBER CS00002JB38
J 0
(9475 5375);
DISPLAY 0.489362 (9475 5375);
PAINT SKYBLUE (9475 5375);
DISPLAY INVISIBLE (9475 5375);
FORCEPROP 1 LAST PACK_TYPE 0402LF
J 0
(9500 5250);
DISPLAY 0.489362 (9500 5250);
PAINT SKYBLUE (9500 5250);
DISPLAY INVISIBLE (9500 5250);
FORCEADD Q_RES..1
(9450 5275);
FORCEPROP 1 LAST LOCATION R2289
J 0
(9250 5275);
DISPLAY 0.489362 (9250 5275);
PAINT SKYBLUE (9250 5275);
FORCEPROP 0 LAST $SEC 1
J 0
(9375 5325);
DISPLAY 0.680851 (9375 5325);
PAINT MONO (9375 5325);
DISPLAY INVISIBLE (9375 5325);
FORCEPROP 0 LAST CDS_SEC 1
J 0
(9375 5325);
DISPLAY 1.021277 (9375 5325);
DISPLAY INVISIBLE (9375 5325);
FORCEPROP 1 LASTPIN (9350 5275) $PN 1
J 0
(9362 5287);
DISPLAY 0.489362 (9362 5287);
PAINT MONO (9362 5287);
FORCEPROP 1 LASTPIN (9550 5275) $PN 2
J 0
(9512 5287);
DISPLAY 0.489362 (9512 5287);
PAINT MONO (9512 5287);
FORCEPROP 1 LAST VALUE 0
J 2
(9575 5275);
DISPLAY 0.489362 (9575 5275);
PAINT SKYBLUE (9575 5275);
FORCEPROP 2 LAST CDS_LIB pure_quanta
J 0
(9450 5275);
DISPLAY INVISIBLE (9450 5275);
FORCEPROP 1 LAST PATH I400
J 0
(9400 5425);
DISPLAY 0.978723 (9400 5425);
PAINT WHITE (9400 5425);
DISPLAY INVISIBLE (9400 5425);
FORCEPROP 1 LAST WATTAGE 1/16W
J 2
(9850 5200);
DISPLAY 0.489362 (9850 5200);
PAINT SKYBLUE (9850 5200);
DISPLAY INVISIBLE (9850 5200);
FORCEPROP 1 LAST MATERIAL CHIP
J 0
(9875 5200);
DISPLAY 0.489362 (9875 5200);
PAINT SKYBLUE (9875 5200);
DISPLAY INVISIBLE (9875 5200);
FORCEPROP 1 LAST TOLERANCE 5%
J 0
(9425 5200);
DISPLAY 0.489362 (9425 5200);
PAINT SKYBLUE (9425 5200);
DISPLAY INVISIBLE (9425 5200);
FORCEPROP 1 LAST PART_NUMBER CS00002JB38
J 0
(9475 5325);
DISPLAY 0.489362 (9475 5325);
PAINT SKYBLUE (9475 5325);
DISPLAY INVISIBLE (9475 5325);
FORCEPROP 1 LAST PACK_TYPE 0402LF
J 0
(9500 5200);
DISPLAY 0.489362 (9500 5200);
PAINT SKYBLUE (9500 5200);
DISPLAY INVISIBLE (9500 5200);
FORCEADD OFFPAGE..2
(10275 5325);
FORCEPROP 2 LAST $XR0 114 
J 0
(10464 5325);
DISPLAY 0.638298 (10464 5325);
PAINT MONO (10464 5325);
FORCEPROP 1 LAST COMMENT_BODY TRUE
J 0
(10230 5230);
DISPLAY 0.872340 (10230 5230);
PAINT GREEN (10230 5230);
DISPLAY INVISIBLE (10230 5230);
FORCEPROP 1 LAST OFFPAGE TRUE
J 0
(10600 5200);
DISPLAY 0.723404 (10600 5200);
PAINT GREEN (10600 5200);
DISPLAY INVISIBLE (10600 5200);
FORCEPROP 2 LAST PATH I401
J 0
(10450 5400);
DISPLAY 1.021277 (10450 5400);
DISPLAY INVISIBLE (10450 5400);
FORCEPROP 2 LAST CDS_LIB standard
J 0
(10275 5325);
DISPLAY INVISIBLE (10275 5325);
FORCEADD OFFPAGE..2
(10275 5275);
FORCEPROP 2 LAST $XR0 114 
J 0
(10464 5275);
DISPLAY 0.638298 (10464 5275);
PAINT MONO (10464 5275);
FORCEPROP 1 LAST COMMENT_BODY TRUE
J 0
(10230 5180);
DISPLAY 0.872340 (10230 5180);
PAINT GREEN (10230 5180);
DISPLAY INVISIBLE (10230 5180);
FORCEPROP 1 LAST OFFPAGE TRUE
J 0
(10600 5150);
DISPLAY 0.723404 (10600 5150);
PAINT GREEN (10600 5150);
DISPLAY INVISIBLE (10600 5150);
FORCEPROP 2 LAST PATH I402
J 0
(10450 5350);
DISPLAY 1.021277 (10450 5350);
DISPLAY INVISIBLE (10450 5350);
FORCEPROP 2 LAST CDS_LIB standard
J 0
(10275 5275);
DISPLAY INVISIBLE (10275 5275);
FORCEADD OFFPAGE..2
(10275 5175);
FORCEPROP 2 LAST $XR0 114 
J 0
(10464 5175);
DISPLAY 0.638298 (10464 5175);
PAINT MONO (10464 5175);
FORCEPROP 1 LAST OFFPAGE TRUE
J 0
(10600 5050);
DISPLAY 0.723404 (10600 5050);
PAINT GREEN (10600 5050);
DISPLAY INVISIBLE (10600 5050);
FORCEPROP 1 LAST COMMENT_BODY TRUE
J 0
(10230 5080);
DISPLAY 0.872340 (10230 5080);
PAINT GREEN (10230 5080);
DISPLAY INVISIBLE (10230 5080);
FORCEPROP 2 LAST PATH I403
J 0
(10450 5250);
DISPLAY 1.021277 (10450 5250);
DISPLAY INVISIBLE (10450 5250);
FORCEPROP 2 LAST CDS_LIB standard
J 0
(10275 5175);
DISPLAY INVISIBLE (10275 5175);
FORCEADD OFFPAGE..2
(10275 5225);
FORCEPROP 2 LAST $XR0 114 
J 0
(10464 5225);
DISPLAY 0.638298 (10464 5225);
PAINT MONO (10464 5225);
FORCEPROP 1 LAST OFFPAGE TRUE
J 0
(10600 5100);
DISPLAY 0.723404 (10600 5100);
PAINT GREEN (10600 5100);
DISPLAY INVISIBLE (10600 5100);
FORCEPROP 1 LAST COMMENT_BODY TRUE
J 0
(10230 5130);
DISPLAY 0.872340 (10230 5130);
PAINT GREEN (10230 5130);
DISPLAY INVISIBLE (10230 5130);
FORCEPROP 2 LAST PATH I404
J 0
(10450 5300);
DISPLAY 1.021277 (10450 5300);
DISPLAY INVISIBLE (10450 5300);
FORCEPROP 2 LAST CDS_LIB standard
J 0
(10275 5225);
DISPLAY INVISIBLE (10275 5225);
FORCEADD Q_RES..1
(9450 5225);
FORCEPROP 1 LAST LOCATION R2290
J 0
(9250 5225);
DISPLAY 0.489362 (9250 5225);
PAINT SKYBLUE (9250 5225);
FORCEPROP 0 LAST $SEC 1
J 0
(9375 5275);
DISPLAY 0.680851 (9375 5275);
PAINT MONO (9375 5275);
DISPLAY INVISIBLE (9375 5275);
FORCEPROP 0 LAST CDS_SEC 1
J 0
(9375 5275);
DISPLAY 1.021277 (9375 5275);
DISPLAY INVISIBLE (9375 5275);
FORCEPROP 1 LASTPIN (9350 5225) $PN 1
J 0
(9362 5237);
DISPLAY 0.489362 (9362 5237);
PAINT MONO (9362 5237);
FORCEPROP 1 LASTPIN (9550 5225) $PN 2
J 0
(9512 5237);
DISPLAY 0.489362 (9512 5237);
PAINT MONO (9512 5237);
FORCEPROP 1 LAST VALUE 0
J 2
(9575 5225);
DISPLAY 0.489362 (9575 5225);
PAINT SKYBLUE (9575 5225);
FORCEPROP 2 LAST CDS_LIB pure_quanta
J 0
(9450 5225);
DISPLAY INVISIBLE (9450 5225);
FORCEPROP 1 LAST PATH I405
J 0
(9400 5375);
DISPLAY 0.978723 (9400 5375);
PAINT WHITE (9400 5375);
DISPLAY INVISIBLE (9400 5375);
FORCEPROP 1 LAST WATTAGE 1/16W
J 2
(9850 5150);
DISPLAY 0.489362 (9850 5150);
PAINT SKYBLUE (9850 5150);
DISPLAY INVISIBLE (9850 5150);
FORCEPROP 1 LAST MATERIAL CHIP
J 0
(9875 5150);
DISPLAY 0.489362 (9875 5150);
PAINT SKYBLUE (9875 5150);
DISPLAY INVISIBLE (9875 5150);
FORCEPROP 1 LAST TOLERANCE 5%
J 0
(9425 5150);
DISPLAY 0.489362 (9425 5150);
PAINT SKYBLUE (9425 5150);
DISPLAY INVISIBLE (9425 5150);
FORCEPROP 1 LAST PART_NUMBER CS00002JB38
J 0
(9475 5275);
DISPLAY 0.489362 (9475 5275);
PAINT SKYBLUE (9475 5275);
DISPLAY INVISIBLE (9475 5275);
FORCEPROP 1 LAST PACK_TYPE 0402LF
J 0
(9500 5150);
DISPLAY 0.489362 (9500 5150);
PAINT SKYBLUE (9500 5150);
DISPLAY INVISIBLE (9500 5150);
FORCEADD Q_RES..1
(9450 5175);
FORCEPROP 1 LAST LOCATION R2291
J 0
(9250 5175);
DISPLAY 0.489362 (9250 5175);
PAINT SKYBLUE (9250 5175);
FORCEPROP 0 LAST $SEC 1
J 0
(9375 5225);
DISPLAY 0.680851 (9375 5225);
PAINT MONO (9375 5225);
DISPLAY INVISIBLE (9375 5225);
FORCEPROP 0 LAST CDS_SEC 1
J 0
(9375 5225);
DISPLAY 1.021277 (9375 5225);
DISPLAY INVISIBLE (9375 5225);
FORCEPROP 1 LASTPIN (9350 5175) $PN 1
J 0
(9362 5187);
DISPLAY 0.489362 (9362 5187);
PAINT MONO (9362 5187);
FORCEPROP 1 LASTPIN (9550 5175) $PN 2
J 0
(9512 5187);
DISPLAY 0.489362 (9512 5187);
PAINT MONO (9512 5187);
FORCEPROP 1 LAST VALUE 0
J 2
(9575 5175);
DISPLAY 0.489362 (9575 5175);
PAINT SKYBLUE (9575 5175);
FORCEPROP 2 LAST CDS_LIB pure_quanta
J 0
(9450 5175);
DISPLAY INVISIBLE (9450 5175);
FORCEPROP 1 LAST PATH I406
J 0
(9400 5325);
DISPLAY 0.978723 (9400 5325);
PAINT WHITE (9400 5325);
DISPLAY INVISIBLE (9400 5325);
FORCEPROP 1 LAST WATTAGE 1/16W
J 2
(9850 5100);
DISPLAY 0.489362 (9850 5100);
PAINT SKYBLUE (9850 5100);
DISPLAY INVISIBLE (9850 5100);
FORCEPROP 1 LAST MATERIAL CHIP
J 0
(9875 5100);
DISPLAY 0.489362 (9875 5100);
PAINT SKYBLUE (9875 5100);
DISPLAY INVISIBLE (9875 5100);
FORCEPROP 1 LAST TOLERANCE 5%
J 0
(9425 5100);
DISPLAY 0.489362 (9425 5100);
PAINT SKYBLUE (9425 5100);
DISPLAY INVISIBLE (9425 5100);
FORCEPROP 1 LAST PART_NUMBER CS00002JB38
J 0
(9475 5225);
DISPLAY 0.489362 (9475 5225);
PAINT SKYBLUE (9475 5225);
DISPLAY INVISIBLE (9475 5225);
FORCEPROP 1 LAST PACK_TYPE 0402LF
J 0
(9500 5100);
DISPLAY 0.489362 (9500 5100);
PAINT SKYBLUE (9500 5100);
DISPLAY INVISIBLE (9500 5100);
FORCEADD Q_RES..1
(9300 2000);
FORCEPROP 1 LAST LOCATION R2287
J 0
(9125 2000);
DISPLAY 0.489362 (9125 2000);
PAINT SKYBLUE (9125 2000);
FORCEPROP 0 LAST $SEC 1
J 0
(9225 2050);
DISPLAY 0.680851 (9225 2050);
PAINT MONO (9225 2050);
DISPLAY INVISIBLE (9225 2050);
FORCEPROP 0 LAST CDS_SEC 1
J 0
(9225 2050);
DISPLAY 1.021277 (9225 2050);
DISPLAY INVISIBLE (9225 2050);
FORCEPROP 1 LASTPIN (9200 2000) $PN 1
J 0
(9212 2012);
DISPLAY 0.489362 (9212 2012);
PAINT MONO (9212 2012);
FORCEPROP 1 LASTPIN (9400 2000) $PN 2
J 0
(9362 2012);
DISPLAY 0.489362 (9362 2012);
PAINT MONO (9362 2012);
FORCEPROP 1 LAST VALUE 0
J 2
(9425 2000);
DISPLAY 0.489362 (9425 2000);
PAINT SKYBLUE (9425 2000);
FORCEPROP 2 LAST CDS_LIB pure_quanta
J 0
(9300 2000);
DISPLAY INVISIBLE (9300 2000);
FORCEPROP 1 LAST PATH I411
J 0
(9250 2150);
DISPLAY 0.978723 (9250 2150);
PAINT WHITE (9250 2150);
DISPLAY INVISIBLE (9250 2150);
FORCEPROP 1 LAST WATTAGE 1/16W
J 2
(9700 1925);
DISPLAY 0.489362 (9700 1925);
PAINT SKYBLUE (9700 1925);
DISPLAY INVISIBLE (9700 1925);
FORCEPROP 1 LAST MATERIAL CHIP
J 0
(9725 1925);
DISPLAY 0.489362 (9725 1925);
PAINT SKYBLUE (9725 1925);
DISPLAY INVISIBLE (9725 1925);
FORCEPROP 1 LAST TOLERANCE 5%
J 0
(9275 1925);
DISPLAY 0.489362 (9275 1925);
PAINT SKYBLUE (9275 1925);
DISPLAY INVISIBLE (9275 1925);
FORCEPROP 1 LAST PART_NUMBER CS00002JB38
J 0
(9325 2050);
DISPLAY 0.489362 (9325 2050);
PAINT SKYBLUE (9325 2050);
DISPLAY INVISIBLE (9325 2050);
FORCEPROP 1 LAST PACK_TYPE 0402LF
J 0
(9350 1925);
DISPLAY 0.489362 (9350 1925);
PAINT SKYBLUE (9350 1925);
DISPLAY INVISIBLE (9350 1925);
FORCEADD Q_RES..1
(9300 2150);
FORCEPROP 1 LAST LOCATION R2284
J 0
(9125 2150);
DISPLAY 0.489362 (9125 2150);
PAINT SKYBLUE (9125 2150);
FORCEPROP 0 LAST $SEC 1
J 0
(9225 2200);
DISPLAY 0.680851 (9225 2200);
PAINT MONO (9225 2200);
DISPLAY INVISIBLE (9225 2200);
FORCEPROP 0 LAST CDS_SEC 1
J 0
(9225 2200);
DISPLAY 1.021277 (9225 2200);
DISPLAY INVISIBLE (9225 2200);
FORCEPROP 1 LASTPIN (9200 2150) $PN 1
J 0
(9212 2162);
DISPLAY 0.489362 (9212 2162);
PAINT MONO (9212 2162);
FORCEPROP 1 LASTPIN (9400 2150) $PN 2
J 0
(9362 2162);
DISPLAY 0.489362 (9362 2162);
PAINT MONO (9362 2162);
FORCEPROP 1 LAST VALUE 0
J 2
(9425 2150);
DISPLAY 0.489362 (9425 2150);
PAINT SKYBLUE (9425 2150);
FORCEPROP 2 LAST CDS_LIB pure_quanta
J 0
(9300 2150);
DISPLAY INVISIBLE (9300 2150);
FORCEPROP 1 LAST PATH I412
J 0
(9250 2300);
DISPLAY 0.978723 (9250 2300);
PAINT WHITE (9250 2300);
DISPLAY INVISIBLE (9250 2300);
FORCEPROP 1 LAST WATTAGE 1/16W
J 2
(9700 2075);
DISPLAY 0.489362 (9700 2075);
PAINT SKYBLUE (9700 2075);
DISPLAY INVISIBLE (9700 2075);
FORCEPROP 1 LAST MATERIAL CHIP
J 0
(9725 2075);
DISPLAY 0.489362 (9725 2075);
PAINT SKYBLUE (9725 2075);
DISPLAY INVISIBLE (9725 2075);
FORCEPROP 1 LAST TOLERANCE 5%
J 0
(9275 2075);
DISPLAY 0.489362 (9275 2075);
PAINT SKYBLUE (9275 2075);
DISPLAY INVISIBLE (9275 2075);
FORCEPROP 1 LAST PART_NUMBER CS00002JB38
J 0
(9325 2200);
DISPLAY 0.489362 (9325 2200);
PAINT SKYBLUE (9325 2200);
DISPLAY INVISIBLE (9325 2200);
FORCEPROP 1 LAST PACK_TYPE 0402LF
J 0
(9350 2075);
DISPLAY 0.489362 (9350 2075);
PAINT SKYBLUE (9350 2075);
DISPLAY INVISIBLE (9350 2075);
FORCEADD Q_RES..1
(9300 2100);
FORCEPROP 1 LAST LOCATION R2285
J 0
(9125 2100);
DISPLAY 0.489362 (9125 2100);
PAINT SKYBLUE (9125 2100);
FORCEPROP 0 LAST $SEC 1
J 0
(9225 2150);
DISPLAY 0.680851 (9225 2150);
PAINT MONO (9225 2150);
DISPLAY INVISIBLE (9225 2150);
FORCEPROP 0 LAST CDS_SEC 1
J 0
(9225 2150);
DISPLAY 1.021277 (9225 2150);
DISPLAY INVISIBLE (9225 2150);
FORCEPROP 1 LASTPIN (9200 2100) $PN 1
J 0
(9212 2112);
DISPLAY 0.489362 (9212 2112);
PAINT MONO (9212 2112);
FORCEPROP 1 LASTPIN (9400 2100) $PN 2
J 0
(9362 2112);
DISPLAY 0.489362 (9362 2112);
PAINT MONO (9362 2112);
FORCEPROP 1 LAST VALUE 0
J 2
(9425 2100);
DISPLAY 0.489362 (9425 2100);
PAINT SKYBLUE (9425 2100);
FORCEPROP 2 LAST CDS_LIB pure_quanta
J 0
(9300 2100);
DISPLAY INVISIBLE (9300 2100);
FORCEPROP 1 LAST PATH I413
J 0
(9250 2250);
DISPLAY 0.978723 (9250 2250);
PAINT WHITE (9250 2250);
DISPLAY INVISIBLE (9250 2250);
FORCEPROP 1 LAST WATTAGE 1/16W
J 2
(9700 2025);
DISPLAY 0.489362 (9700 2025);
PAINT SKYBLUE (9700 2025);
DISPLAY INVISIBLE (9700 2025);
FORCEPROP 1 LAST MATERIAL CHIP
J 0
(9725 2025);
DISPLAY 0.489362 (9725 2025);
PAINT SKYBLUE (9725 2025);
DISPLAY INVISIBLE (9725 2025);
FORCEPROP 1 LAST TOLERANCE 5%
J 0
(9275 2025);
DISPLAY 0.489362 (9275 2025);
PAINT SKYBLUE (9275 2025);
DISPLAY INVISIBLE (9275 2025);
FORCEPROP 1 LAST PART_NUMBER CS00002JB38
J 0
(9325 2150);
DISPLAY 0.489362 (9325 2150);
PAINT SKYBLUE (9325 2150);
DISPLAY INVISIBLE (9325 2150);
FORCEPROP 1 LAST PACK_TYPE 0402LF
J 0
(9350 2025);
DISPLAY 0.489362 (9350 2025);
PAINT SKYBLUE (9350 2025);
DISPLAY INVISIBLE (9350 2025);
FORCEADD Q_RES..1
(9300 2050);
FORCEPROP 1 LAST LOCATION R2286
J 0
(9125 2050);
DISPLAY 0.489362 (9125 2050);
PAINT SKYBLUE (9125 2050);
FORCEPROP 0 LAST $SEC 1
J 0
(9225 2100);
DISPLAY 0.680851 (9225 2100);
PAINT MONO (9225 2100);
DISPLAY INVISIBLE (9225 2100);
FORCEPROP 0 LAST CDS_SEC 1
J 0
(9225 2100);
DISPLAY 1.021277 (9225 2100);
DISPLAY INVISIBLE (9225 2100);
FORCEPROP 1 LASTPIN (9200 2050) $PN 1
J 0
(9212 2062);
DISPLAY 0.489362 (9212 2062);
PAINT MONO (9212 2062);
FORCEPROP 1 LASTPIN (9400 2050) $PN 2
J 0
(9362 2062);
DISPLAY 0.489362 (9362 2062);
PAINT MONO (9362 2062);
FORCEPROP 1 LAST VALUE 0
J 2
(9425 2050);
DISPLAY 0.489362 (9425 2050);
PAINT SKYBLUE (9425 2050);
FORCEPROP 2 LAST CDS_LIB pure_quanta
J 0
(9300 2050);
DISPLAY INVISIBLE (9300 2050);
FORCEPROP 1 LAST PATH I414
J 0
(9250 2200);
DISPLAY 0.978723 (9250 2200);
PAINT WHITE (9250 2200);
DISPLAY INVISIBLE (9250 2200);
FORCEPROP 1 LAST WATTAGE 1/16W
J 2
(9700 1975);
DISPLAY 0.489362 (9700 1975);
PAINT SKYBLUE (9700 1975);
DISPLAY INVISIBLE (9700 1975);
FORCEPROP 1 LAST MATERIAL CHIP
J 0
(9725 1975);
DISPLAY 0.489362 (9725 1975);
PAINT SKYBLUE (9725 1975);
DISPLAY INVISIBLE (9725 1975);
FORCEPROP 1 LAST TOLERANCE 5%
J 0
(9275 1975);
DISPLAY 0.489362 (9275 1975);
PAINT SKYBLUE (9275 1975);
DISPLAY INVISIBLE (9275 1975);
FORCEPROP 1 LAST PART_NUMBER CS00002JB38
J 0
(9325 2100);
DISPLAY 0.489362 (9325 2100);
PAINT SKYBLUE (9325 2100);
DISPLAY INVISIBLE (9325 2100);
FORCEPROP 1 LAST PACK_TYPE 0402LF
J 0
(9350 1975);
DISPLAY 0.489362 (9350 1975);
PAINT SKYBLUE (9350 1975);
DISPLAY INVISIBLE (9350 1975);
FORCEADD OFFPAGE..2
(10175 2150);
FORCEPROP 2 LAST $XR0 115 
J 0
(10364 2150);
DISPLAY 0.638298 (10364 2150);
PAINT MONO (10364 2150);
FORCEPROP 2 LAST CDS_LIB standard
J 0
(10175 2150);
DISPLAY INVISIBLE (10175 2150);
FORCEPROP 2 LAST PATH I415
J 0
(10350 2225);
DISPLAY 1.021277 (10350 2225);
DISPLAY INVISIBLE (10350 2225);
FORCEPROP 1 LAST COMMENT_BODY TRUE
J 0
(10130 2055);
DISPLAY 0.872340 (10130 2055);
PAINT GREEN (10130 2055);
DISPLAY INVISIBLE (10130 2055);
FORCEPROP 1 LAST OFFPAGE TRUE
J 0
(10500 2025);
DISPLAY 0.723404 (10500 2025);
PAINT GREEN (10500 2025);
DISPLAY INVISIBLE (10500 2025);
FORCEADD OFFPAGE..2
(10175 2100);
FORCEPROP 2 LAST $XR0 115 
J 0
(10364 2100);
DISPLAY 0.638298 (10364 2100);
PAINT MONO (10364 2100);
FORCEPROP 2 LAST CDS_LIB standard
J 0
(10175 2100);
DISPLAY INVISIBLE (10175 2100);
FORCEPROP 2 LAST PATH I416
J 0
(10350 2175);
DISPLAY 1.021277 (10350 2175);
DISPLAY INVISIBLE (10350 2175);
FORCEPROP 1 LAST OFFPAGE TRUE
J 0
(10500 1975);
DISPLAY 0.723404 (10500 1975);
PAINT GREEN (10500 1975);
DISPLAY INVISIBLE (10500 1975);
FORCEPROP 1 LAST COMMENT_BODY TRUE
J 0
(10130 2005);
DISPLAY 0.872340 (10130 2005);
PAINT GREEN (10130 2005);
DISPLAY INVISIBLE (10130 2005);
FORCEADD OFFPAGE..2
(10175 2050);
FORCEPROP 2 LAST $XR0 115 
J 0
(10364 2050);
DISPLAY 0.638298 (10364 2050);
PAINT MONO (10364 2050);
FORCEPROP 2 LAST CDS_LIB standard
J 0
(10175 2050);
DISPLAY INVISIBLE (10175 2050);
FORCEPROP 2 LAST PATH I417
J 0
(10350 2125);
DISPLAY 1.021277 (10350 2125);
DISPLAY INVISIBLE (10350 2125);
FORCEPROP 1 LAST OFFPAGE TRUE
J 0
(10500 1925);
DISPLAY 0.723404 (10500 1925);
PAINT GREEN (10500 1925);
DISPLAY INVISIBLE (10500 1925);
FORCEPROP 1 LAST COMMENT_BODY TRUE
J 0
(10130 1955);
DISPLAY 0.872340 (10130 1955);
PAINT GREEN (10130 1955);
DISPLAY INVISIBLE (10130 1955);
FORCEADD OFFPAGE..2
(10175 2000);
FORCEPROP 2 LAST $XR0 115 
J 0
(10364 2000);
DISPLAY 0.638298 (10364 2000);
PAINT MONO (10364 2000);
FORCEPROP 2 LAST CDS_LIB standard
J 0
(10175 2000);
DISPLAY INVISIBLE (10175 2000);
FORCEPROP 2 LAST PATH I418
J 0
(10350 2075);
DISPLAY 1.021277 (10350 2075);
DISPLAY INVISIBLE (10350 2075);
FORCEPROP 1 LAST OFFPAGE TRUE
J 0
(10500 1875);
DISPLAY 0.723404 (10500 1875);
PAINT GREEN (10500 1875);
DISPLAY INVISIBLE (10500 1875);
FORCEPROP 1 LAST COMMENT_BODY TRUE
J 0
(10130 1905);
DISPLAY 0.872340 (10130 1905);
PAINT GREEN (10130 1905);
DISPLAY INVISIBLE (10130 1905);
FORCEADD UNIVERSAL_POWER..1
(9275 3000);
FORCEPROP 3 LASTPIN (9275 2950) SIG_NAME P3V3\g
J 0
(9285 2960);
DISPLAY 0.659574 (9285 2960);
PAINT MONO (9285 2960);
DISPLAY INVISIBLE (9285 2960);
FORCEPROP 1 LAST HDL_POWER P3V3
J 1
(9275 3050);
DISPLAY 0.489362 (9275 3050);
PAINT GREEN (9275 3050);
FORCEPROP 2 LAST CDS_LIB pure_quanta_power
J 0
(9275 3000);
DISPLAY INVISIBLE (9275 3000);
FORCEPROP 1 LAST PATH I419
J 0
(9325 3025);
DISPLAY 0.872340 (9325 3025);
PAINT AQUA (9325 3025);
DISPLAY INVISIBLE (9325 3025);
FORCEADD Q_RES..2
(9275 2800);
FORCEPROP 1 LAST LOCATION R119
J 0
(9320 2925);
DISPLAY 0.489362 (9320 2925);
PAINT SKYBLUE (9320 2925);
FORCEPROP 0 LAST $SEC 1
J 0
(9325 2975);
DISPLAY 0.680851 (9325 2975);
PAINT MONO (9325 2975);
DISPLAY INVISIBLE (9325 2975);
FORCEPROP 0 LAST CDS_SEC 1
J 0
(9325 2975);
DISPLAY 1.021277 (9325 2975);
DISPLAY INVISIBLE (9325 2975);
FORCEPROP 1 LASTPIN (9275 2900) $PN 1
J 0
(9280 2862);
DISPLAY 0.489362 (9280 2862);
PAINT MONO (9280 2862);
FORCEPROP 1 LASTPIN (9275 2700) $PN 2
J 0
(9280 2710);
DISPLAY 0.489362 (9280 2710);
PAINT MONO (9280 2710);
FORCEPROP 1 LAST WATTAGE 1/16W
J 0
(9315 2775);
DISPLAY 0.489362 (9315 2775);
PAINT SKYBLUE (9315 2775);
FORCEPROP 1 LAST MATERIAL CHIP
J 0
(9315 2725);
DISPLAY 0.489362 (9315 2725);
PAINT SKYBLUE (9315 2725);
FORCEPROP 1 LAST TOLERANCE 5%
J 0
(9320 2825);
DISPLAY 0.489362 (9320 2825);
PAINT SKYBLUE (9320 2825);
FORCEPROP 1 LAST VALUE 10K
J 0
(9320 2875);
DISPLAY 0.489362 (9320 2875);
PAINT SKYBLUE (9320 2875);
FORCEPROP 1 LAST PACK_TYPE 0402LF
J 0
(9325 2675);
DISPLAY 0.489362 (9325 2675);
PAINT SKYBLUE (9325 2675);
FORCEPROP 2 LAST CDS_LIB pure_quanta
J 0
(9275 2800);
DISPLAY INVISIBLE (9275 2800);
FORCEPROP 1 LAST PATH I420
J 0
(9325 2975);
DISPLAY 0.978723 (9325 2975);
PAINT WHITE (9325 2975);
DISPLAY INVISIBLE (9325 2975);
FORCEPROP 1 LAST PART_NUMBER TMP_QCS31002JB28
J 0
(9315 2675);
DISPLAY 0.489362 (9315 2675);
PAINT SKYBLUE (9315 2675);
DISPLAY INVISIBLE (9315 2675);
FORCEADD Q_RES..2
(9275 2450);
FORCEPROP 1 LAST LOCATION R120
J 0
(9320 2575);
DISPLAY 0.489362 (9320 2575);
PAINT SKYBLUE (9320 2575);
FORCEPROP 0 LAST $SEC 1
J 0
(9325 2625);
DISPLAY 0.680851 (9325 2625);
PAINT MONO (9325 2625);
DISPLAY INVISIBLE (9325 2625);
FORCEPROP 0 LAST CDS_SEC 1
J 0
(9325 2625);
DISPLAY 1.021277 (9325 2625);
DISPLAY INVISIBLE (9325 2625);
FORCEPROP 1 LASTPIN (9275 2550) $PN 1
J 0
(9280 2512);
DISPLAY 0.489362 (9280 2512);
PAINT MONO (9280 2512);
FORCEPROP 1 LASTPIN (9275 2350) $PN 2
J 0
(9280 2360);
DISPLAY 0.489362 (9280 2360);
PAINT MONO (9280 2360);
FORCEPROP 1 LAST WATTAGE 1/16W
J 0
(9315 2425);
DISPLAY 0.489362 (9315 2425);
PAINT SKYBLUE (9315 2425);
FORCEPROP 1 LAST MATERIAL CHIP
J 0
(9315 2375);
DISPLAY 0.489362 (9315 2375);
PAINT SKYBLUE (9315 2375);
FORCEPROP 1 LAST TOLERANCE 5%
J 0
(9320 2475);
DISPLAY 0.489362 (9320 2475);
PAINT SKYBLUE (9320 2475);
FORCEPROP 1 LAST VALUE 10K
J 0
(9320 2525);
DISPLAY 0.489362 (9320 2525);
PAINT SKYBLUE (9320 2525);
FORCEPROP 1 LAST PACK_TYPE 0402LF
J 0
(9325 2325);
DISPLAY 0.489362 (9325 2325);
PAINT SKYBLUE (9325 2325);
FORCEPROP 2 LAST CDS_LIB pure_quanta
J 0
(9275 2450);
DISPLAY INVISIBLE (9275 2450);
FORCEPROP 1 LAST PATH I421
J 0
(9325 2625);
DISPLAY 0.978723 (9325 2625);
PAINT WHITE (9325 2625);
DISPLAY INVISIBLE (9325 2625);
FORCEPROP 1 LAST PART_NUMBER TMP_QCS31002JB28
J 0
(9315 2325);
DISPLAY 0.489362 (9315 2325);
PAINT SKYBLUE (9315 2325);
DISPLAY INVISIBLE (9315 2325);
FORCEADD UNIVERSAL_GND..1
(9275 2300);
FORCEPROP 3 LASTPIN (9275 2350) SIG_NAME GND\g
J 0
(9285 2360);
DISPLAY 0.659574 (9285 2360);
PAINT MONO (9285 2360);
DISPLAY INVISIBLE (9285 2360);
FORCEPROP 1 LAST HDL_POWER GND
J 1
(9300 2225);
DISPLAY 0.489362 (9300 2225);
PAINT GREEN (9300 2225);
FORCEPROP 2 LAST CDS_LIB pure_quanta_power
J 0
(9275 2300);
DISPLAY INVISIBLE (9275 2300);
FORCEPROP 1 LAST PATH I422
J 0
(9350 2300);
DISPLAY 0.872340 (9350 2300);
PAINT AQUA (9350 2300);
DISPLAY INVISIBLE (9350 2300);
FORCEADD Q_RES..2
(9200 5950);
FORCEPROP 1 LAST LOCATION R117
J 0
(9245 6075);
DISPLAY 0.489362 (9245 6075);
PAINT SKYBLUE (9245 6075);
FORCEPROP 0 LAST $SEC 1
J 0
(9250 6125);
DISPLAY 0.680851 (9250 6125);
PAINT MONO (9250 6125);
DISPLAY INVISIBLE (9250 6125);
FORCEPROP 0 LAST CDS_SEC 1
J 0
(9250 6125);
DISPLAY 1.021277 (9250 6125);
DISPLAY INVISIBLE (9250 6125);
FORCEPROP 1 LASTPIN (9200 6050) $PN 1
J 0
(9205 6012);
DISPLAY 0.489362 (9205 6012);
PAINT MONO (9205 6012);
FORCEPROP 1 LASTPIN (9200 5850) $PN 2
J 0
(9205 5860);
DISPLAY 0.489362 (9205 5860);
PAINT MONO (9205 5860);
FORCEPROP 1 LAST WATTAGE 1/16W
J 0
(9240 5925);
DISPLAY 0.489362 (9240 5925);
PAINT SKYBLUE (9240 5925);
FORCEPROP 1 LAST MATERIAL CHIP
J 0
(9240 5875);
DISPLAY 0.489362 (9240 5875);
PAINT SKYBLUE (9240 5875);
FORCEPROP 1 LAST TOLERANCE 5%
J 0
(9245 5975);
DISPLAY 0.489362 (9245 5975);
PAINT SKYBLUE (9245 5975);
FORCEPROP 1 LAST VALUE 10K
J 0
(9245 6025);
DISPLAY 0.489362 (9245 6025);
PAINT SKYBLUE (9245 6025);
FORCEPROP 1 LAST PACK_TYPE 0402LF
J 0
(9250 5825);
DISPLAY 0.489362 (9250 5825);
PAINT SKYBLUE (9250 5825);
FORCEPROP 2 LAST CDS_LIB pure_quanta
J 0
(9200 5950);
DISPLAY INVISIBLE (9200 5950);
FORCEPROP 1 LAST PATH I423
J 0
(9250 6125);
DISPLAY 0.978723 (9250 6125);
PAINT WHITE (9250 6125);
DISPLAY INVISIBLE (9250 6125);
FORCEPROP 1 LAST PART_NUMBER TMP_QCS31002JB28
J 0
(9240 5825);
DISPLAY 0.489362 (9240 5825);
PAINT SKYBLUE (9240 5825);
DISPLAY INVISIBLE (9240 5825);
FORCEADD Q_RES..2
(9200 5600);
FORCEPROP 1 LAST LOCATION R118
J 0
(9245 5725);
DISPLAY 0.489362 (9245 5725);
PAINT SKYBLUE (9245 5725);
FORCEPROP 0 LAST $SEC 1
J 0
(9250 5775);
DISPLAY 0.680851 (9250 5775);
PAINT MONO (9250 5775);
DISPLAY INVISIBLE (9250 5775);
FORCEPROP 0 LAST CDS_SEC 1
J 0
(9250 5775);
DISPLAY 1.021277 (9250 5775);
DISPLAY INVISIBLE (9250 5775);
FORCEPROP 1 LASTPIN (9200 5700) $PN 1
J 0
(9205 5662);
DISPLAY 0.489362 (9205 5662);
PAINT MONO (9205 5662);
FORCEPROP 1 LASTPIN (9200 5500) $PN 2
J 0
(9205 5510);
DISPLAY 0.489362 (9205 5510);
PAINT MONO (9205 5510);
FORCEPROP 1 LAST WATTAGE 1/16W
J 0
(9240 5575);
DISPLAY 0.489362 (9240 5575);
PAINT SKYBLUE (9240 5575);
FORCEPROP 1 LAST MATERIAL CHIP
J 0
(9240 5525);
DISPLAY 0.489362 (9240 5525);
PAINT SKYBLUE (9240 5525);
FORCEPROP 1 LAST TOLERANCE 5%
J 0
(9245 5625);
DISPLAY 0.489362 (9245 5625);
PAINT SKYBLUE (9245 5625);
FORCEPROP 1 LAST VALUE 10K
J 0
(9245 5675);
DISPLAY 0.489362 (9245 5675);
PAINT SKYBLUE (9245 5675);
FORCEPROP 1 LAST PACK_TYPE 0402LF
J 0
(9250 5475);
DISPLAY 0.489362 (9250 5475);
PAINT SKYBLUE (9250 5475);
FORCEPROP 2 LAST CDS_LIB pure_quanta
J 0
(9200 5600);
DISPLAY INVISIBLE (9200 5600);
FORCEPROP 1 LAST PATH I424
J 0
(9250 5775);
DISPLAY 0.978723 (9250 5775);
PAINT WHITE (9250 5775);
DISPLAY INVISIBLE (9250 5775);
FORCEPROP 1 LAST PART_NUMBER TMP_QCS31002JB28
J 0
(9240 5475);
DISPLAY 0.489362 (9240 5475);
PAINT SKYBLUE (9240 5475);
DISPLAY INVISIBLE (9240 5475);
FORCEADD UNIVERSAL_POWER..1
(9200 6150);
FORCEPROP 3 LASTPIN (9200 6100) SIG_NAME P3V3\g
J 0
(9210 6110);
DISPLAY 0.659574 (9210 6110);
PAINT MONO (9210 6110);
DISPLAY INVISIBLE (9210 6110);
FORCEPROP 1 LAST HDL_POWER P3V3
J 1
(9200 6200);
DISPLAY 0.489362 (9200 6200);
PAINT GREEN (9200 6200);
FORCEPROP 2 LAST CDS_LIB pure_quanta_power
J 0
(9200 6150);
DISPLAY INVISIBLE (9200 6150);
FORCEPROP 1 LAST PATH I425
J 0
(9250 6175);
DISPLAY 0.872340 (9250 6175);
PAINT AQUA (9250 6175);
DISPLAY INVISIBLE (9250 6175);
FORCEADD UNIVERSAL_GND..1
(9200 5450);
FORCEPROP 3 LASTPIN (9200 5500) SIG_NAME GND\g
J 0
(9210 5510);
DISPLAY 0.659574 (9210 5510);
PAINT MONO (9210 5510);
DISPLAY INVISIBLE (9210 5510);
FORCEPROP 1 LAST HDL_POWER GND
J 1
(9225 5375);
DISPLAY 0.489362 (9225 5375);
PAINT GREEN (9225 5375);
FORCEPROP 2 LAST CDS_LIB pure_quanta_power
J 0
(9200 5450);
DISPLAY INVISIBLE (9200 5450);
FORCEPROP 1 LAST PATH I426
J 0
(9275 5450);
DISPLAY 0.872340 (9275 5450);
PAINT AQUA (9275 5450);
DISPLAY INVISIBLE (9275 5450);
FORCEADD UNIVERSAL_GND..1
(8400 4275);
FORCEPROP 3 LASTPIN (8400 4325) SIG_NAME GND\g
J 0
(8410 4335);
DISPLAY 0.659574 (8410 4335);
PAINT MONO (8410 4335);
DISPLAY INVISIBLE (8410 4335);
FORCEPROP 1 LAST HDL_POWER GND
J 1
(8425 4200);
DISPLAY 0.489362 (8425 4200);
PAINT GREEN (8425 4200);
FORCEPROP 2 LAST CDS_LIB pure_quanta_power
J 0
(8400 4275);
DISPLAY INVISIBLE (8400 4275);
FORCEPROP 1 LAST PATH I427
J 0
(8475 4275);
DISPLAY 0.872340 (8475 4275);
PAINT AQUA (8475 4275);
DISPLAY INVISIBLE (8475 4275);
FORCEADD UNIVERSAL_GND..1
(8425 1100);
FORCEPROP 3 LASTPIN (8425 1150) SIG_NAME GND\g
J 0
(8435 1160);
DISPLAY 0.659574 (8435 1160);
PAINT MONO (8435 1160);
DISPLAY INVISIBLE (8435 1160);
FORCEPROP 1 LAST HDL_POWER GND
J 1
(8450 1025);
DISPLAY 0.489362 (8450 1025);
PAINT GREEN (8450 1025);
FORCEPROP 2 LAST CDS_LIB pure_quanta_power
J 0
(8425 1100);
DISPLAY INVISIBLE (8425 1100);
FORCEPROP 1 LAST PATH I428
J 0
(8500 1100);
DISPLAY 0.872340 (8500 1100);
PAINT AQUA (8500 1100);
DISPLAY INVISIBLE (8500 1100);
FORCEADD UNIVERSAL_POWER..1
(2825 3875);
FORCEPROP 3 LASTPIN (2825 3825) SIG_NAME P3V3\g
J 0
(2835 3835);
DISPLAY 0.659574 (2835 3835);
PAINT MONO (2835 3835);
DISPLAY INVISIBLE (2835 3835);
FORCEPROP 1 LAST HDL_POWER P3V3
J 1
(2825 3925);
DISPLAY 0.489362 (2825 3925);
PAINT GREEN (2825 3925);
FORCEPROP 2 LAST CDS_LIB pure_quanta_power
J 0
(2825 3875);
DISPLAY INVISIBLE (2825 3875);
FORCEPROP 1 LAST PATH I429
J 0
(2875 3900);
DISPLAY 0.872340 (2875 3900);
PAINT AQUA (2875 3900);
DISPLAY INVISIBLE (2875 3900);
FORCEADD UNIVERSAL_GND..1
(2825 3025);
FORCEPROP 3 LASTPIN (2825 3075) SIG_NAME GND\g
J 0
(2835 3085);
DISPLAY 0.659574 (2835 3085);
PAINT MONO (2835 3085);
DISPLAY INVISIBLE (2835 3085);
FORCEPROP 2 LAST CDS_LIB pure_quanta_power
J 0
(2825 3025);
DISPLAY INVISIBLE (2825 3025);
FORCEPROP 1 LAST PATH I432
J 0
(2900 3025);
DISPLAY 0.872340 (2900 3025);
PAINT AQUA (2900 3025);
DISPLAY INVISIBLE (2900 3025);
FORCEPROP 1 LAST HDL_POWER GND
J 1
(2850 2950);
DISPLAY 0.872340 (2850 2950);
PAINT GREEN (2850 2950);
DISPLAY INVISIBLE (2850 2950);
FORCEADD Q_RES..2
(2825 3200);
FORCEPROP 1 LAST LOCATION R592
J 0
(2870 3325);
DISPLAY 0.489362 (2870 3325);
PAINT SKYBLUE (2870 3325);
FORCEPROP 0 LAST $SEC 1
J 0
(2875 3375);
DISPLAY 0.680851 (2875 3375);
PAINT MONO (2875 3375);
DISPLAY INVISIBLE (2875 3375);
FORCEPROP 0 LAST CDS_SEC 1
J 0
(2875 3375);
DISPLAY 1.021277 (2875 3375);
DISPLAY INVISIBLE (2875 3375);
FORCEPROP 1 LASTPIN (2825 3300) $PN 1
J 0
(2830 3262);
DISPLAY 0.489362 (2830 3262);
PAINT MONO (2830 3262);
FORCEPROP 1 LASTPIN (2825 3100) $PN 2
J 0
(2830 3110);
DISPLAY 0.489362 (2830 3110);
PAINT MONO (2830 3110);
FORCEPROP 1 LAST WATTAGE 1/16W
J 0
(2865 3175);
DISPLAY 0.489362 (2865 3175);
PAINT SKYBLUE (2865 3175);
FORCEPROP 1 LAST MATERIAL CHIP
J 0
(2865 3125);
DISPLAY 0.489362 (2865 3125);
PAINT SKYBLUE (2865 3125);
FORCEPROP 1 LAST TOLERANCE 5%
J 0
(2870 3225);
DISPLAY 0.489362 (2870 3225);
PAINT SKYBLUE (2870 3225);
FORCEPROP 1 LAST VALUE 1K
J 0
(2870 3275);
DISPLAY 0.489362 (2870 3275);
PAINT SKYBLUE (2870 3275);
FORCEPROP 1 LAST PACK_TYPE 0402LF
J 0
(2865 3075);
DISPLAY 0.489362 (2865 3075);
PAINT SKYBLUE (2865 3075);
FORCEPROP 2 LAST CDS_LIB pure_quanta
J 0
(2825 3200);
DISPLAY INVISIBLE (2825 3200);
FORCEPROP 1 LAST PATH I433
J 0
(2875 3375);
DISPLAY 0.978723 (2875 3375);
PAINT WHITE (2875 3375);
DISPLAY INVISIBLE (2875 3375);
FORCEPROP 1 LAST PART_NUMBER TMP_QCS21002JB34
J 0
(2865 3025);
DISPLAY 0.638298 (2865 3025);
PAINT SKYBLUE (2865 3025);
DISPLAY INVISIBLE (2865 3025);
FORCEADD Q_RES..2
(2825 3625);
FORCEPROP 1 LAST LOCATION R591
J 0
(2870 3750);
DISPLAY 0.489362 (2870 3750);
PAINT SKYBLUE (2870 3750);
FORCEPROP 0 LAST $SEC 1
J 0
(2875 3800);
DISPLAY 0.680851 (2875 3800);
PAINT MONO (2875 3800);
DISPLAY INVISIBLE (2875 3800);
FORCEPROP 0 LAST CDS_SEC 1
J 0
(2875 3800);
DISPLAY 1.021277 (2875 3800);
DISPLAY INVISIBLE (2875 3800);
FORCEPROP 1 LASTPIN (2825 3725) $PN 1
J 0
(2830 3687);
DISPLAY 0.489362 (2830 3687);
PAINT MONO (2830 3687);
FORCEPROP 1 LASTPIN (2825 3525) $PN 2
J 0
(2830 3535);
DISPLAY 0.489362 (2830 3535);
PAINT MONO (2830 3535);
FORCEPROP 1 LAST WATTAGE 1/16W
J 0
(2865 3600);
DISPLAY 0.489362 (2865 3600);
PAINT SKYBLUE (2865 3600);
FORCEPROP 1 LAST MATERIAL EMPTY
J 0
(2865 3550);
DISPLAY 0.489362 (2865 3550);
PAINT RED (2865 3550);
FORCEPROP 1 LAST TOLERANCE 5%
J 0
(2870 3650);
DISPLAY 0.489362 (2870 3650);
PAINT SKYBLUE (2870 3650);
FORCEPROP 1 LAST VALUE 1K
J 0
(2870 3700);
DISPLAY 0.489362 (2870 3700);
PAINT SKYBLUE (2870 3700);
FORCEPROP 1 LAST PACK_TYPE 0402LF
J 0
(2865 3500);
DISPLAY 0.489362 (2865 3500);
PAINT SKYBLUE (2865 3500);
FORCEPROP 2 LAST CDS_LIB pure_quanta
J 0
(2825 3625);
DISPLAY INVISIBLE (2825 3625);
FORCEPROP 1 LAST PATH I434
J 0
(2875 3800);
DISPLAY 0.978723 (2875 3800);
PAINT WHITE (2875 3800);
DISPLAY INVISIBLE (2875 3800);
FORCEPROP 1 LAST PART_NUMBER TMP_QCS21002JB34
J 0
(2865 3450);
DISPLAY 0.638298 (2865 3450);
PAINT SKYBLUE (2865 3450);
DISPLAY INVISIBLE (2865 3450);
FORCEADD UNIVERSAL_POWER..1
(3050 3875);
FORCEPROP 3 LASTPIN (3050 3825) SIG_NAME P3V3\g
J 0
(3060 3835);
DISPLAY 0.659574 (3060 3835);
PAINT MONO (3060 3835);
DISPLAY INVISIBLE (3060 3835);
FORCEPROP 1 LAST HDL_POWER P3V3
J 1
(3050 3925);
DISPLAY 0.489362 (3050 3925);
PAINT GREEN (3050 3925);
FORCEPROP 2 LAST CDS_LIB pure_quanta_power
J 0
(3050 3875);
DISPLAY INVISIBLE (3050 3875);
FORCEPROP 1 LAST PATH I435
J 0
(3100 3900);
DISPLAY 0.872340 (3100 3900);
PAINT AQUA (3100 3900);
DISPLAY INVISIBLE (3100 3900);
FORCEADD UNIVERSAL_GND..1
(3050 3025);
FORCEPROP 3 LASTPIN (3050 3075) SIG_NAME GND\g
J 0
(3060 3085);
DISPLAY 0.659574 (3060 3085);
PAINT MONO (3060 3085);
DISPLAY INVISIBLE (3060 3085);
FORCEPROP 2 LAST CDS_LIB pure_quanta_power
J 0
(3050 3025);
DISPLAY INVISIBLE (3050 3025);
FORCEPROP 1 LAST PATH I437
J 0
(3125 3025);
DISPLAY 0.872340 (3125 3025);
PAINT AQUA (3125 3025);
DISPLAY INVISIBLE (3125 3025);
FORCEPROP 1 LAST HDL_POWER GND
J 1
(3075 2950);
DISPLAY 0.872340 (3075 2950);
PAINT GREEN (3075 2950);
DISPLAY INVISIBLE (3075 2950);
FORCEADD Q_RES..2
(3050 3200);
FORCEPROP 1 LAST LOCATION R594
J 0
(3095 3325);
DISPLAY 0.489362 (3095 3325);
PAINT SKYBLUE (3095 3325);
FORCEPROP 0 LAST $SEC 1
J 0
(3100 3375);
DISPLAY 0.680851 (3100 3375);
PAINT MONO (3100 3375);
DISPLAY INVISIBLE (3100 3375);
FORCEPROP 0 LAST CDS_SEC 1
J 0
(3100 3375);
DISPLAY 1.021277 (3100 3375);
DISPLAY INVISIBLE (3100 3375);
FORCEPROP 1 LASTPIN (3050 3300) $PN 1
J 0
(3055 3262);
DISPLAY 0.489362 (3055 3262);
PAINT MONO (3055 3262);
FORCEPROP 1 LASTPIN (3050 3100) $PN 2
J 0
(3055 3110);
DISPLAY 0.489362 (3055 3110);
PAINT MONO (3055 3110);
FORCEPROP 1 LAST WATTAGE 1/16W
J 0
(3090 3175);
DISPLAY 0.489362 (3090 3175);
PAINT SKYBLUE (3090 3175);
FORCEPROP 1 LAST MATERIAL CHIP
J 0
(3090 3125);
DISPLAY 0.489362 (3090 3125);
PAINT SKYBLUE (3090 3125);
FORCEPROP 1 LAST TOLERANCE 5%
J 0
(3095 3225);
DISPLAY 0.489362 (3095 3225);
PAINT SKYBLUE (3095 3225);
FORCEPROP 1 LAST VALUE 1K
J 0
(3095 3275);
DISPLAY 0.489362 (3095 3275);
PAINT SKYBLUE (3095 3275);
FORCEPROP 1 LAST PACK_TYPE 0402LF
J 0
(3090 3075);
DISPLAY 0.489362 (3090 3075);
PAINT SKYBLUE (3090 3075);
FORCEPROP 2 LAST CDS_LIB pure_quanta
J 0
(3050 3200);
DISPLAY INVISIBLE (3050 3200);
FORCEPROP 1 LAST PATH I438
J 0
(3100 3375);
DISPLAY 0.978723 (3100 3375);
PAINT WHITE (3100 3375);
DISPLAY INVISIBLE (3100 3375);
FORCEPROP 1 LAST PART_NUMBER TMP_QCS21002JB34
J 0
(3090 3025);
DISPLAY 0.638298 (3090 3025);
PAINT SKYBLUE (3090 3025);
DISPLAY INVISIBLE (3090 3025);
FORCEADD OFFPAGE..1
(6250 1900);
FORCEPROP 2 LAST $XR0 110 
J 0
(5998 1900);
DISPLAY 0.638298 (5998 1900);
PAINT MONO (5998 1900);
FORCEPROP 1 LAST OFFPAGE TRUE
J 0
(6575 1775);
DISPLAY 0.872340 (6575 1775);
PAINT GREEN (6575 1775);
DISPLAY INVISIBLE (6575 1775);
FORCEPROP 1 LAST COMMENT_BODY TRUE
J 0
(6375 1800);
DISPLAY 0.872340 (6375 1800);
PAINT GREEN (6375 1800);
DISPLAY INVISIBLE (6375 1800);
FORCEPROP 2 LAST PATH I439
J 0
(6300 1975);
DISPLAY 1.021277 (6300 1975);
DISPLAY INVISIBLE (6300 1975);
FORCEPROP 2 LAST CDS_LIB standard
J 0
(6250 1900);
DISPLAY INVISIBLE (6250 1900);
FORCEADD OFFPAGE..1
(6225 5075);
FORCEPROP 2 LAST $XR0 110 
J 0
(5973 5075);
DISPLAY 0.638298 (5973 5075);
PAINT MONO (5973 5075);
FORCEPROP 2 LAST CDS_LIB standard
J 0
(6225 5075);
DISPLAY INVISIBLE (6225 5075);
FORCEPROP 2 LAST PATH I440
J 0
(6275 5150);
DISPLAY 1.021277 (6275 5150);
DISPLAY INVISIBLE (6275 5150);
FORCEPROP 1 LAST OFFPAGE TRUE
J 0
(6550 4950);
DISPLAY 0.872340 (6550 4950);
PAINT GREEN (6550 4950);
DISPLAY INVISIBLE (6550 4950);
FORCEPROP 1 LAST COMMENT_BODY TRUE
J 0
(6350 4975);
DISPLAY 0.872340 (6350 4975);
PAINT GREEN (6350 4975);
DISPLAY INVISIBLE (6350 4975);
FORCEADD Q_RES..1
(9450 4975);
FORCEPROP 1 LAST LOCATION R151
J 0
(9250 4975);
DISPLAY 0.489362 (9250 4975);
PAINT SKYBLUE (9250 4975);
FORCEPROP 0 LAST $SEC 1
J 0
(9575 5000);
DISPLAY 0.680851 (9575 5000);
PAINT MONO (9575 5000);
DISPLAY INVISIBLE (9575 5000);
FORCEPROP 0 LAST CDS_SEC 1
J 0
(9575 5000);
DISPLAY 1.021277 (9575 5000);
DISPLAY INVISIBLE (9575 5000);
FORCEPROP 1 LASTPIN (9350 4975) $PN 1
J 0
(9362 4987);
DISPLAY 0.489362 (9362 4987);
PAINT MONO (9362 4987);
FORCEPROP 1 LASTPIN (9550 4975) $PN 2
J 0
(9512 4987);
DISPLAY 0.489362 (9512 4987);
PAINT MONO (9512 4987);
FORCEPROP 1 LAST VALUE 0
J 2
(9575 4975);
DISPLAY 0.489362 (9575 4975);
PAINT SKYBLUE (9575 4975);
FORCEPROP 2 LAST CDS_LIB pure_quanta
J 0
(9450 4975);
DISPLAY INVISIBLE (9450 4975);
FORCEPROP 1 LAST PATH I441
J 0
(9400 5125);
DISPLAY 0.978723 (9400 5125);
PAINT WHITE (9400 5125);
DISPLAY INVISIBLE (9400 5125);
FORCEPROP 1 LAST WATTAGE 1/16W
J 2
(9850 4900);
DISPLAY 0.489362 (9850 4900);
PAINT SKYBLUE (9850 4900);
DISPLAY INVISIBLE (9850 4900);
FORCEPROP 1 LAST MATERIAL CHIP
J 0
(9875 4900);
DISPLAY 0.489362 (9875 4900);
PAINT SKYBLUE (9875 4900);
DISPLAY INVISIBLE (9875 4900);
FORCEPROP 1 LAST TOLERANCE 5%
J 0
(9425 4900);
DISPLAY 0.489362 (9425 4900);
PAINT SKYBLUE (9425 4900);
DISPLAY INVISIBLE (9425 4900);
FORCEPROP 1 LAST PART_NUMBER CS00002JB38
J 0
(9475 5025);
DISPLAY 0.489362 (9475 5025);
PAINT SKYBLUE (9475 5025);
DISPLAY INVISIBLE (9475 5025);
FORCEPROP 1 LAST PACK_TYPE 0402LF
J 0
(9500 4900);
DISPLAY 0.489362 (9500 4900);
PAINT SKYBLUE (9500 4900);
DISPLAY INVISIBLE (9500 4900);
FORCEADD Q_RES..1
(9450 5025);
FORCEPROP 1 LAST LOCATION R150
J 0
(9250 5025);
DISPLAY 0.489362 (9250 5025);
PAINT SKYBLUE (9250 5025);
FORCEPROP 0 LAST $SEC 1
J 0
(9575 5050);
DISPLAY 0.680851 (9575 5050);
PAINT MONO (9575 5050);
DISPLAY INVISIBLE (9575 5050);
FORCEPROP 0 LAST CDS_SEC 1
J 0
(9575 5050);
DISPLAY 1.021277 (9575 5050);
DISPLAY INVISIBLE (9575 5050);
FORCEPROP 1 LASTPIN (9350 5025) $PN 1
J 0
(9362 5037);
DISPLAY 0.489362 (9362 5037);
PAINT MONO (9362 5037);
FORCEPROP 1 LASTPIN (9550 5025) $PN 2
J 0
(9512 5037);
DISPLAY 0.489362 (9512 5037);
PAINT MONO (9512 5037);
FORCEPROP 1 LAST VALUE 0
J 2
(9575 5025);
DISPLAY 0.489362 (9575 5025);
PAINT SKYBLUE (9575 5025);
FORCEPROP 2 LAST CDS_LIB pure_quanta
J 0
(9450 5025);
DISPLAY INVISIBLE (9450 5025);
FORCEPROP 1 LAST PATH I442
J 0
(9400 5175);
DISPLAY 0.978723 (9400 5175);
PAINT WHITE (9400 5175);
DISPLAY INVISIBLE (9400 5175);
FORCEPROP 1 LAST WATTAGE 1/16W
J 2
(9850 4950);
DISPLAY 0.489362 (9850 4950);
PAINT SKYBLUE (9850 4950);
DISPLAY INVISIBLE (9850 4950);
FORCEPROP 1 LAST MATERIAL CHIP
J 0
(9875 4950);
DISPLAY 0.489362 (9875 4950);
PAINT SKYBLUE (9875 4950);
DISPLAY INVISIBLE (9875 4950);
FORCEPROP 1 LAST TOLERANCE 5%
J 0
(9425 4950);
DISPLAY 0.489362 (9425 4950);
PAINT SKYBLUE (9425 4950);
DISPLAY INVISIBLE (9425 4950);
FORCEPROP 1 LAST PART_NUMBER CS00002JB38
J 0
(9475 5075);
DISPLAY 0.489362 (9475 5075);
PAINT SKYBLUE (9475 5075);
DISPLAY INVISIBLE (9475 5075);
FORCEPROP 1 LAST PACK_TYPE 0402LF
J 0
(9500 4950);
DISPLAY 0.489362 (9500 4950);
PAINT SKYBLUE (9500 4950);
DISPLAY INVISIBLE (9500 4950);
FORCEADD Q_RES..1
(9450 5075);
FORCEPROP 1 LAST LOCATION R149
J 0
(9250 5075);
DISPLAY 0.489362 (9250 5075);
PAINT SKYBLUE (9250 5075);
FORCEPROP 0 LAST $SEC 1
J 0
(9575 5100);
DISPLAY 0.680851 (9575 5100);
PAINT MONO (9575 5100);
DISPLAY INVISIBLE (9575 5100);
FORCEPROP 0 LAST CDS_SEC 1
J 0
(9575 5100);
DISPLAY 1.021277 (9575 5100);
DISPLAY INVISIBLE (9575 5100);
FORCEPROP 1 LASTPIN (9350 5075) $PN 1
J 0
(9362 5087);
DISPLAY 0.489362 (9362 5087);
PAINT MONO (9362 5087);
FORCEPROP 1 LASTPIN (9550 5075) $PN 2
J 0
(9512 5087);
DISPLAY 0.489362 (9512 5087);
PAINT MONO (9512 5087);
FORCEPROP 1 LAST VALUE 0
J 2
(9575 5075);
DISPLAY 0.489362 (9575 5075);
PAINT SKYBLUE (9575 5075);
FORCEPROP 2 LAST CDS_LIB pure_quanta
J 0
(9450 5075);
DISPLAY INVISIBLE (9450 5075);
FORCEPROP 1 LAST PATH I443
J 0
(9400 5225);
DISPLAY 0.978723 (9400 5225);
PAINT WHITE (9400 5225);
DISPLAY INVISIBLE (9400 5225);
FORCEPROP 1 LAST WATTAGE 1/16W
J 2
(9850 5000);
DISPLAY 0.489362 (9850 5000);
PAINT SKYBLUE (9850 5000);
DISPLAY INVISIBLE (9850 5000);
FORCEPROP 1 LAST MATERIAL CHIP
J 0
(9875 5000);
DISPLAY 0.489362 (9875 5000);
PAINT SKYBLUE (9875 5000);
DISPLAY INVISIBLE (9875 5000);
FORCEPROP 1 LAST TOLERANCE 5%
J 0
(9425 5000);
DISPLAY 0.489362 (9425 5000);
PAINT SKYBLUE (9425 5000);
DISPLAY INVISIBLE (9425 5000);
FORCEPROP 1 LAST PART_NUMBER CS00002JB38
J 0
(9475 5125);
DISPLAY 0.489362 (9475 5125);
PAINT SKYBLUE (9475 5125);
DISPLAY INVISIBLE (9475 5125);
FORCEPROP 1 LAST PACK_TYPE 0402LF
J 0
(9500 5000);
DISPLAY 0.489362 (9500 5000);
PAINT SKYBLUE (9500 5000);
DISPLAY INVISIBLE (9500 5000);
FORCEADD Q_RES..1
(9450 5125);
FORCEPROP 1 LAST LOCATION R69
J 0
(9250 5125);
DISPLAY 0.489362 (9250 5125);
PAINT SKYBLUE (9250 5125);
FORCEPROP 0 LAST $SEC 1
J 0
(9575 5150);
DISPLAY 0.680851 (9575 5150);
PAINT MONO (9575 5150);
DISPLAY INVISIBLE (9575 5150);
FORCEPROP 0 LAST CDS_SEC 1
J 0
(9575 5150);
DISPLAY 1.021277 (9575 5150);
DISPLAY INVISIBLE (9575 5150);
FORCEPROP 1 LASTPIN (9350 5125) $PN 1
J 0
(9362 5137);
DISPLAY 0.489362 (9362 5137);
PAINT MONO (9362 5137);
FORCEPROP 1 LASTPIN (9550 5125) $PN 2
J 0
(9512 5137);
DISPLAY 0.489362 (9512 5137);
PAINT MONO (9512 5137);
FORCEPROP 1 LAST VALUE 0
J 2
(9575 5125);
DISPLAY 0.489362 (9575 5125);
PAINT SKYBLUE (9575 5125);
FORCEPROP 2 LAST CDS_LIB pure_quanta
J 0
(9450 5125);
DISPLAY INVISIBLE (9450 5125);
FORCEPROP 1 LAST PATH I444
J 0
(9400 5275);
DISPLAY 0.978723 (9400 5275);
PAINT WHITE (9400 5275);
DISPLAY INVISIBLE (9400 5275);
FORCEPROP 1 LAST WATTAGE 1/16W
J 2
(9850 5050);
DISPLAY 0.489362 (9850 5050);
PAINT SKYBLUE (9850 5050);
DISPLAY INVISIBLE (9850 5050);
FORCEPROP 1 LAST MATERIAL CHIP
J 0
(9875 5050);
DISPLAY 0.489362 (9875 5050);
PAINT SKYBLUE (9875 5050);
DISPLAY INVISIBLE (9875 5050);
FORCEPROP 1 LAST TOLERANCE 5%
J 0
(9425 5050);
DISPLAY 0.489362 (9425 5050);
PAINT SKYBLUE (9425 5050);
DISPLAY INVISIBLE (9425 5050);
FORCEPROP 1 LAST PART_NUMBER CS00002JB38
J 0
(9475 5175);
DISPLAY 0.489362 (9475 5175);
PAINT SKYBLUE (9475 5175);
DISPLAY INVISIBLE (9475 5175);
FORCEPROP 1 LAST PACK_TYPE 0402LF
J 0
(9500 5050);
DISPLAY 0.489362 (9500 5050);
PAINT SKYBLUE (9500 5050);
DISPLAY INVISIBLE (9500 5050);
FORCEADD OFFPAGE..2
(10275 5125);
FORCEPROP 2 LAST $XR0 114 
J 0
(10464 5125);
DISPLAY 0.638298 (10464 5125);
PAINT MONO (10464 5125);
FORCEPROP 2 LAST CDS_LIB standard
J 0
(10275 5125);
DISPLAY INVISIBLE (10275 5125);
FORCEPROP 2 LAST PATH I445
J 0
(10450 5200);
DISPLAY 1.021277 (10450 5200);
DISPLAY INVISIBLE (10450 5200);
FORCEPROP 1 LAST OFFPAGE TRUE
J 0
(10600 5000);
DISPLAY 0.723404 (10600 5000);
PAINT GREEN (10600 5000);
DISPLAY INVISIBLE (10600 5000);
FORCEPROP 1 LAST COMMENT_BODY TRUE
J 0
(10230 5030);
DISPLAY 0.872340 (10230 5030);
PAINT GREEN (10230 5030);
DISPLAY INVISIBLE (10230 5030);
FORCEADD OFFPAGE..2
(10275 5075);
FORCEPROP 2 LAST $XR0 114 
J 0
(10464 5075);
DISPLAY 0.638298 (10464 5075);
PAINT MONO (10464 5075);
FORCEPROP 2 LAST CDS_LIB standard
J 0
(10275 5075);
DISPLAY INVISIBLE (10275 5075);
FORCEPROP 2 LAST PATH I446
J 0
(10450 5150);
DISPLAY 1.021277 (10450 5150);
DISPLAY INVISIBLE (10450 5150);
FORCEPROP 1 LAST OFFPAGE TRUE
J 0
(10600 4950);
DISPLAY 0.723404 (10600 4950);
PAINT GREEN (10600 4950);
DISPLAY INVISIBLE (10600 4950);
FORCEPROP 1 LAST COMMENT_BODY TRUE
J 0
(10230 4980);
DISPLAY 0.872340 (10230 4980);
PAINT GREEN (10230 4980);
DISPLAY INVISIBLE (10230 4980);
FORCEADD OFFPAGE..2
(10275 4975);
FORCEPROP 2 LAST $XR0 114 
J 0
(10464 4975);
DISPLAY 0.638298 (10464 4975);
PAINT MONO (10464 4975);
FORCEPROP 2 LAST CDS_LIB standard
J 0
(10275 4975);
DISPLAY INVISIBLE (10275 4975);
FORCEPROP 2 LAST PATH I447
J 0
(10450 5050);
DISPLAY 1.021277 (10450 5050);
DISPLAY INVISIBLE (10450 5050);
FORCEPROP 1 LAST COMMENT_BODY TRUE
J 0
(10230 4880);
DISPLAY 0.872340 (10230 4880);
PAINT GREEN (10230 4880);
DISPLAY INVISIBLE (10230 4880);
FORCEPROP 1 LAST OFFPAGE TRUE
J 0
(10600 4850);
DISPLAY 0.723404 (10600 4850);
PAINT GREEN (10600 4850);
DISPLAY INVISIBLE (10600 4850);
FORCEADD OFFPAGE..2
(10275 5025);
FORCEPROP 2 LAST $XR0 114 
J 0
(10464 5025);
DISPLAY 0.638298 (10464 5025);
PAINT MONO (10464 5025);
FORCEPROP 2 LAST CDS_LIB standard
J 0
(10275 5025);
DISPLAY INVISIBLE (10275 5025);
FORCEPROP 2 LAST PATH I448
J 0
(10450 5100);
DISPLAY 1.021277 (10450 5100);
DISPLAY INVISIBLE (10450 5100);
FORCEPROP 1 LAST COMMENT_BODY TRUE
J 0
(10230 4930);
DISPLAY 0.872340 (10230 4930);
PAINT GREEN (10230 4930);
DISPLAY INVISIBLE (10230 4930);
FORCEPROP 1 LAST OFFPAGE TRUE
J 0
(10600 4900);
DISPLAY 0.723404 (10600 4900);
PAINT GREEN (10600 4900);
DISPLAY INVISIBLE (10600 4900);
FORCEADD Q_RES..1
(9300 1800);
FORCEPROP 1 LAST LOCATION R68
J 0
(9125 1800);
DISPLAY 0.489362 (9125 1800);
PAINT SKYBLUE (9125 1800);
FORCEPROP 0 LAST $SEC 1
J 0
(9425 1825);
DISPLAY 0.680851 (9425 1825);
PAINT MONO (9425 1825);
DISPLAY INVISIBLE (9425 1825);
FORCEPROP 0 LAST CDS_SEC 1
J 0
(9425 1825);
DISPLAY 1.021277 (9425 1825);
DISPLAY INVISIBLE (9425 1825);
FORCEPROP 1 LASTPIN (9200 1800) $PN 1
J 0
(9212 1812);
DISPLAY 0.489362 (9212 1812);
PAINT MONO (9212 1812);
FORCEPROP 1 LASTPIN (9400 1800) $PN 2
J 0
(9362 1812);
DISPLAY 0.489362 (9362 1812);
PAINT MONO (9362 1812);
FORCEPROP 1 LAST VALUE 0
J 2
(9425 1800);
DISPLAY 0.489362 (9425 1800);
PAINT SKYBLUE (9425 1800);
FORCEPROP 2 LAST CDS_LIB pure_quanta
J 0
(9300 1800);
DISPLAY INVISIBLE (9300 1800);
FORCEPROP 1 LAST PATH I449
J 0
(9250 1950);
DISPLAY 0.978723 (9250 1950);
PAINT WHITE (9250 1950);
DISPLAY INVISIBLE (9250 1950);
FORCEPROP 1 LAST WATTAGE 1/16W
J 2
(9700 1725);
DISPLAY 0.489362 (9700 1725);
PAINT SKYBLUE (9700 1725);
DISPLAY INVISIBLE (9700 1725);
FORCEPROP 1 LAST MATERIAL CHIP
J 0
(9725 1725);
DISPLAY 0.489362 (9725 1725);
PAINT SKYBLUE (9725 1725);
DISPLAY INVISIBLE (9725 1725);
FORCEPROP 1 LAST TOLERANCE 5%
J 0
(9275 1725);
DISPLAY 0.489362 (9275 1725);
PAINT SKYBLUE (9275 1725);
DISPLAY INVISIBLE (9275 1725);
FORCEPROP 1 LAST PART_NUMBER CS00002JB38
J 0
(9325 1850);
DISPLAY 0.489362 (9325 1850);
PAINT SKYBLUE (9325 1850);
DISPLAY INVISIBLE (9325 1850);
FORCEPROP 1 LAST PACK_TYPE 0402LF
J 0
(9350 1725);
DISPLAY 0.489362 (9350 1725);
PAINT SKYBLUE (9350 1725);
DISPLAY INVISIBLE (9350 1725);
FORCEADD Q_RES..1
(9300 1850);
FORCEPROP 1 LAST LOCATION R67
J 0
(9125 1850);
DISPLAY 0.489362 (9125 1850);
PAINT SKYBLUE (9125 1850);
FORCEPROP 0 LAST $SEC 1
J 0
(9425 1875);
DISPLAY 0.680851 (9425 1875);
PAINT MONO (9425 1875);
DISPLAY INVISIBLE (9425 1875);
FORCEPROP 0 LAST CDS_SEC 1
J 0
(9425 1875);
DISPLAY 1.021277 (9425 1875);
DISPLAY INVISIBLE (9425 1875);
FORCEPROP 1 LASTPIN (9200 1850) $PN 1
J 0
(9212 1862);
DISPLAY 0.489362 (9212 1862);
PAINT MONO (9212 1862);
FORCEPROP 1 LASTPIN (9400 1850) $PN 2
J 0
(9362 1862);
DISPLAY 0.489362 (9362 1862);
PAINT MONO (9362 1862);
FORCEPROP 1 LAST VALUE 0
J 2
(9425 1850);
DISPLAY 0.489362 (9425 1850);
PAINT SKYBLUE (9425 1850);
FORCEPROP 2 LAST CDS_LIB pure_quanta
J 0
(9300 1850);
DISPLAY INVISIBLE (9300 1850);
FORCEPROP 1 LAST PATH I450
J 0
(9250 2000);
DISPLAY 0.978723 (9250 2000);
PAINT WHITE (9250 2000);
DISPLAY INVISIBLE (9250 2000);
FORCEPROP 1 LAST WATTAGE 1/16W
J 2
(9700 1775);
DISPLAY 0.489362 (9700 1775);
PAINT SKYBLUE (9700 1775);
DISPLAY INVISIBLE (9700 1775);
FORCEPROP 1 LAST MATERIAL CHIP
J 0
(9725 1775);
DISPLAY 0.489362 (9725 1775);
PAINT SKYBLUE (9725 1775);
DISPLAY INVISIBLE (9725 1775);
FORCEPROP 1 LAST TOLERANCE 5%
J 0
(9275 1775);
DISPLAY 0.489362 (9275 1775);
PAINT SKYBLUE (9275 1775);
DISPLAY INVISIBLE (9275 1775);
FORCEPROP 1 LAST PART_NUMBER CS00002JB38
J 0
(9325 1900);
DISPLAY 0.489362 (9325 1900);
PAINT SKYBLUE (9325 1900);
DISPLAY INVISIBLE (9325 1900);
FORCEPROP 1 LAST PACK_TYPE 0402LF
J 0
(9350 1775);
DISPLAY 0.489362 (9350 1775);
PAINT SKYBLUE (9350 1775);
DISPLAY INVISIBLE (9350 1775);
FORCEADD Q_RES..1
(9300 1900);
FORCEPROP 1 LAST LOCATION R66
J 0
(9125 1900);
DISPLAY 0.489362 (9125 1900);
PAINT SKYBLUE (9125 1900);
FORCEPROP 0 LAST $SEC 1
J 0
(9425 1925);
DISPLAY 0.680851 (9425 1925);
PAINT MONO (9425 1925);
DISPLAY INVISIBLE (9425 1925);
FORCEPROP 0 LAST CDS_SEC 1
J 0
(9425 1925);
DISPLAY 1.021277 (9425 1925);
DISPLAY INVISIBLE (9425 1925);
FORCEPROP 1 LASTPIN (9200 1900) $PN 1
J 0
(9212 1912);
DISPLAY 0.489362 (9212 1912);
PAINT MONO (9212 1912);
FORCEPROP 1 LASTPIN (9400 1900) $PN 2
J 0
(9362 1912);
DISPLAY 0.489362 (9362 1912);
PAINT MONO (9362 1912);
FORCEPROP 1 LAST VALUE 0
J 2
(9425 1900);
DISPLAY 0.489362 (9425 1900);
PAINT SKYBLUE (9425 1900);
FORCEPROP 2 LAST CDS_LIB pure_quanta
J 0
(9300 1900);
DISPLAY INVISIBLE (9300 1900);
FORCEPROP 1 LAST PATH I451
J 0
(9250 2050);
DISPLAY 0.978723 (9250 2050);
PAINT WHITE (9250 2050);
DISPLAY INVISIBLE (9250 2050);
FORCEPROP 1 LAST WATTAGE 1/16W
J 2
(9700 1825);
DISPLAY 0.489362 (9700 1825);
PAINT SKYBLUE (9700 1825);
DISPLAY INVISIBLE (9700 1825);
FORCEPROP 1 LAST MATERIAL CHIP
J 0
(9725 1825);
DISPLAY 0.489362 (9725 1825);
PAINT SKYBLUE (9725 1825);
DISPLAY INVISIBLE (9725 1825);
FORCEPROP 1 LAST TOLERANCE 5%
J 0
(9275 1825);
DISPLAY 0.489362 (9275 1825);
PAINT SKYBLUE (9275 1825);
DISPLAY INVISIBLE (9275 1825);
FORCEPROP 1 LAST PART_NUMBER CS00002JB38
J 0
(9325 1950);
DISPLAY 0.489362 (9325 1950);
PAINT SKYBLUE (9325 1950);
DISPLAY INVISIBLE (9325 1950);
FORCEPROP 1 LAST PACK_TYPE 0402LF
J 0
(9350 1825);
DISPLAY 0.489362 (9350 1825);
PAINT SKYBLUE (9350 1825);
DISPLAY INVISIBLE (9350 1825);
FORCEADD Q_RES..1
(9300 1950);
FORCEPROP 1 LAST LOCATION R65
J 0
(9125 1950);
DISPLAY 0.489362 (9125 1950);
PAINT SKYBLUE (9125 1950);
FORCEPROP 0 LAST $SEC 1
J 0
(9425 1975);
DISPLAY 0.680851 (9425 1975);
PAINT MONO (9425 1975);
DISPLAY INVISIBLE (9425 1975);
FORCEPROP 0 LAST CDS_SEC 1
J 0
(9425 1975);
DISPLAY 1.021277 (9425 1975);
DISPLAY INVISIBLE (9425 1975);
FORCEPROP 1 LASTPIN (9200 1950) $PN 1
J 0
(9212 1962);
DISPLAY 0.489362 (9212 1962);
PAINT MONO (9212 1962);
FORCEPROP 1 LASTPIN (9400 1950) $PN 2
J 0
(9362 1962);
DISPLAY 0.489362 (9362 1962);
PAINT MONO (9362 1962);
FORCEPROP 1 LAST VALUE 0
J 2
(9425 1950);
DISPLAY 0.489362 (9425 1950);
PAINT SKYBLUE (9425 1950);
FORCEPROP 2 LAST CDS_LIB pure_quanta
J 0
(9300 1950);
DISPLAY INVISIBLE (9300 1950);
FORCEPROP 1 LAST PATH I452
J 0
(9250 2100);
DISPLAY 0.978723 (9250 2100);
PAINT WHITE (9250 2100);
DISPLAY INVISIBLE (9250 2100);
FORCEPROP 1 LAST WATTAGE 1/16W
J 2
(9700 1875);
DISPLAY 0.489362 (9700 1875);
PAINT SKYBLUE (9700 1875);
DISPLAY INVISIBLE (9700 1875);
FORCEPROP 1 LAST MATERIAL CHIP
J 0
(9725 1875);
DISPLAY 0.489362 (9725 1875);
PAINT SKYBLUE (9725 1875);
DISPLAY INVISIBLE (9725 1875);
FORCEPROP 1 LAST TOLERANCE 5%
J 0
(9275 1875);
DISPLAY 0.489362 (9275 1875);
PAINT SKYBLUE (9275 1875);
DISPLAY INVISIBLE (9275 1875);
FORCEPROP 1 LAST PART_NUMBER CS00002JB38
J 0
(9325 2000);
DISPLAY 0.489362 (9325 2000);
PAINT SKYBLUE (9325 2000);
DISPLAY INVISIBLE (9325 2000);
FORCEPROP 1 LAST PACK_TYPE 0402LF
J 0
(9350 1875);
DISPLAY 0.489362 (9350 1875);
PAINT SKYBLUE (9350 1875);
DISPLAY INVISIBLE (9350 1875);
FORCEADD OFFPAGE..2
(10175 1800);
FORCEPROP 2 LAST $XR0 115 
J 0
(10364 1800);
DISPLAY 0.638298 (10364 1800);
PAINT MONO (10364 1800);
FORCEPROP 1 LAST COMMENT_BODY TRUE
J 0
(10130 1705);
DISPLAY 0.872340 (10130 1705);
PAINT GREEN (10130 1705);
DISPLAY INVISIBLE (10130 1705);
FORCEPROP 1 LAST OFFPAGE TRUE
J 0
(10500 1675);
DISPLAY 0.723404 (10500 1675);
PAINT GREEN (10500 1675);
DISPLAY INVISIBLE (10500 1675);
FORCEPROP 2 LAST PATH I453
J 0
(10350 1875);
DISPLAY 1.021277 (10350 1875);
DISPLAY INVISIBLE (10350 1875);
FORCEPROP 2 LAST CDS_LIB standard
J 0
(10175 1800);
DISPLAY INVISIBLE (10175 1800);
FORCEADD OFFPAGE..2
(10175 1950);
FORCEPROP 2 LAST $XR0 115 
J 0
(10364 1950);
DISPLAY 0.638298 (10364 1950);
PAINT MONO (10364 1950);
FORCEPROP 1 LAST COMMENT_BODY TRUE
J 0
(10130 1855);
DISPLAY 0.872340 (10130 1855);
PAINT GREEN (10130 1855);
DISPLAY INVISIBLE (10130 1855);
FORCEPROP 1 LAST OFFPAGE TRUE
J 0
(10500 1825);
DISPLAY 0.723404 (10500 1825);
PAINT GREEN (10500 1825);
DISPLAY INVISIBLE (10500 1825);
FORCEPROP 2 LAST PATH I454
J 0
(10350 2025);
DISPLAY 1.021277 (10350 2025);
DISPLAY INVISIBLE (10350 2025);
FORCEPROP 2 LAST CDS_LIB standard
J 0
(10175 1950);
DISPLAY INVISIBLE (10175 1950);
FORCEADD OFFPAGE..2
(10175 1900);
FORCEPROP 2 LAST $XR0 115 
J 0
(10364 1900);
DISPLAY 0.638298 (10364 1900);
PAINT MONO (10364 1900);
FORCEPROP 1 LAST COMMENT_BODY TRUE
J 0
(10130 1805);
DISPLAY 0.872340 (10130 1805);
PAINT GREEN (10130 1805);
DISPLAY INVISIBLE (10130 1805);
FORCEPROP 1 LAST OFFPAGE TRUE
J 0
(10500 1775);
DISPLAY 0.723404 (10500 1775);
PAINT GREEN (10500 1775);
DISPLAY INVISIBLE (10500 1775);
FORCEPROP 2 LAST PATH I455
J 0
(10350 1975);
DISPLAY 1.021277 (10350 1975);
DISPLAY INVISIBLE (10350 1975);
FORCEPROP 2 LAST CDS_LIB standard
J 0
(10175 1900);
DISPLAY INVISIBLE (10175 1900);
FORCEADD OFFPAGE..2
(10175 1850);
FORCEPROP 2 LAST $XR0 115 
J 0
(10364 1850);
DISPLAY 0.638298 (10364 1850);
PAINT MONO (10364 1850);
FORCEPROP 1 LAST COMMENT_BODY TRUE
J 0
(10130 1755);
DISPLAY 0.872340 (10130 1755);
PAINT GREEN (10130 1755);
DISPLAY INVISIBLE (10130 1755);
FORCEPROP 1 LAST OFFPAGE TRUE
J 0
(10500 1725);
DISPLAY 0.723404 (10500 1725);
PAINT GREEN (10500 1725);
DISPLAY INVISIBLE (10500 1725);
FORCEPROP 2 LAST PATH I456
J 0
(10350 1925);
DISPLAY 1.021277 (10350 1925);
DISPLAY INVISIBLE (10350 1925);
FORCEPROP 2 LAST CDS_LIB standard
J 0
(10175 1850);
DISPLAY INVISIBLE (10175 1850);
FORCEADD Q_RES..1
(6225 4925);
FORCEPROP 1 LAST LOCATION R593
J 0
(6025 4925);
DISPLAY 0.489362 (6025 4925);
PAINT SKYBLUE (6025 4925);
FORCEPROP 0 LAST $SEC 1
J 0
(6100 4975);
DISPLAY 0.680851 (6100 4975);
PAINT MONO (6100 4975);
DISPLAY INVISIBLE (6100 4975);
FORCEPROP 0 LAST CDS_SEC 1
J 0
(6100 4975);
DISPLAY 1.021277 (6100 4975);
DISPLAY INVISIBLE (6100 4975);
FORCEPROP 1 LASTPIN (6125 4925) $PN 1
J 0
(6137 4937);
DISPLAY 0.489362 (6137 4937);
PAINT MONO (6137 4937);
FORCEPROP 1 LASTPIN (6325 4925) $PN 2
J 0
(6287 4937);
DISPLAY 0.489362 (6287 4937);
PAINT MONO (6287 4937);
FORCEPROP 1 LAST VALUE 0
J 2
(6350 4925);
DISPLAY 0.489362 (6350 4925);
PAINT SKYBLUE (6350 4925);
FORCEPROP 2 LAST CDS_LIB pure_quanta
J 0
(6225 4925);
DISPLAY INVISIBLE (6225 4925);
FORCEPROP 1 LAST PATH I458
J 0
(6175 5075);
DISPLAY 0.978723 (6175 5075);
PAINT WHITE (6175 5075);
DISPLAY INVISIBLE (6175 5075);
FORCEPROP 1 LAST WATTAGE 1/16W
J 2
(6625 4850);
DISPLAY 0.489362 (6625 4850);
PAINT SKYBLUE (6625 4850);
DISPLAY INVISIBLE (6625 4850);
FORCEPROP 1 LAST MATERIAL CHIP
J 0
(6650 4850);
DISPLAY 0.489362 (6650 4850);
PAINT SKYBLUE (6650 4850);
DISPLAY INVISIBLE (6650 4850);
FORCEPROP 1 LAST TOLERANCE 5%
J 0
(6200 4850);
DISPLAY 0.489362 (6200 4850);
PAINT SKYBLUE (6200 4850);
DISPLAY INVISIBLE (6200 4850);
FORCEPROP 1 LAST PART_NUMBER CS00002JB38
J 0
(6250 4975);
DISPLAY 0.489362 (6250 4975);
PAINT SKYBLUE (6250 4975);
DISPLAY INVISIBLE (6250 4975);
FORCEPROP 1 LAST PACK_TYPE 0402LF
J 0
(6275 4850);
DISPLAY 0.489362 (6275 4850);
PAINT SKYBLUE (6275 4850);
DISPLAY INVISIBLE (6275 4850);
FORCEADD Q_RES..1
(6225 4975);
FORCEPROP 1 LAST LOCATION R290
J 0
(6025 4975);
DISPLAY 0.489362 (6025 4975);
PAINT SKYBLUE (6025 4975);
FORCEPROP 0 LAST $SEC 1
J 0
(6100 5025);
DISPLAY 0.680851 (6100 5025);
PAINT MONO (6100 5025);
DISPLAY INVISIBLE (6100 5025);
FORCEPROP 0 LAST CDS_SEC 1
J 0
(6100 5025);
DISPLAY 1.021277 (6100 5025);
DISPLAY INVISIBLE (6100 5025);
FORCEPROP 1 LASTPIN (6125 4975) $PN 1
J 0
(6137 4987);
DISPLAY 0.489362 (6137 4987);
PAINT MONO (6137 4987);
FORCEPROP 1 LASTPIN (6325 4975) $PN 2
J 0
(6287 4987);
DISPLAY 0.489362 (6287 4987);
PAINT MONO (6287 4987);
FORCEPROP 1 LAST VALUE 0
J 2
(6350 4975);
DISPLAY 0.489362 (6350 4975);
PAINT SKYBLUE (6350 4975);
FORCEPROP 2 LAST CDS_LIB pure_quanta
J 0
(6225 4975);
DISPLAY INVISIBLE (6225 4975);
FORCEPROP 1 LAST PATH I459
J 0
(6175 5125);
DISPLAY 0.978723 (6175 5125);
PAINT WHITE (6175 5125);
DISPLAY INVISIBLE (6175 5125);
FORCEPROP 1 LAST WATTAGE 1/16W
J 2
(6625 4900);
DISPLAY 0.489362 (6625 4900);
PAINT SKYBLUE (6625 4900);
DISPLAY INVISIBLE (6625 4900);
FORCEPROP 1 LAST MATERIAL CHIP
J 0
(6650 4900);
DISPLAY 0.489362 (6650 4900);
PAINT SKYBLUE (6650 4900);
DISPLAY INVISIBLE (6650 4900);
FORCEPROP 1 LAST TOLERANCE 5%
J 0
(6200 4900);
DISPLAY 0.489362 (6200 4900);
PAINT SKYBLUE (6200 4900);
DISPLAY INVISIBLE (6200 4900);
FORCEPROP 1 LAST PART_NUMBER CS00002JB38
J 0
(6250 5025);
DISPLAY 0.489362 (6250 5025);
PAINT SKYBLUE (6250 5025);
DISPLAY INVISIBLE (6250 5025);
FORCEPROP 1 LAST PACK_TYPE 0402LF
J 0
(6275 4900);
DISPLAY 0.489362 (6275 4900);
PAINT SKYBLUE (6275 4900);
DISPLAY INVISIBLE (6275 4900);
FORCEADD OFFPAGE..1
(5425 4925);
FORCEPROP 2 LAST $XR1 110 
J 0
(5023 4925);
DISPLAY 0.638298 (5023 4925);
PAINT MONO (5023 4925);
FORCEPROP 2 LAST $XR0 111 
J 0
(5143 4925);
DISPLAY 0.638298 (5143 4925);
PAINT MONO (5143 4925);
FORCEPROP 2 LAST CDS_LIB standard
J 0
(5425 4925);
DISPLAY INVISIBLE (5425 4925);
FORCEPROP 2 LAST PATH I460
J 0
(5475 5000);
DISPLAY 1.021277 (5475 5000);
DISPLAY INVISIBLE (5475 5000);
FORCEPROP 1 LAST COMMENT_BODY TRUE
J 0
(5550 4825);
DISPLAY 0.872340 (5550 4825);
PAINT GREEN (5550 4825);
DISPLAY INVISIBLE (5550 4825);
FORCEPROP 1 LAST OFFPAGE TRUE
J 0
(5750 4800);
DISPLAY 0.872340 (5750 4800);
PAINT GREEN (5750 4800);
DISPLAY INVISIBLE (5750 4800);
FORCEADD OFFPAGE..3
R 2
(5425 4975);
FORCEPROP 2 LAST $XR1 111 
J 0
(5025 4975);
DISPLAY 0.638298 (5025 4975);
PAINT MONO (5025 4975);
FORCEPROP 2 LAST $XR0 110 
J 0
(5145 4975);
DISPLAY 0.638298 (5145 4975);
PAINT MONO (5145 4975);
FORCEPROP 2 LAST PATH I461
J 0
(5475 5050);
DISPLAY 1.021277 (5475 5050);
DISPLAY INVISIBLE (5475 5050);
FORCEPROP 1 LAST COMMENT_BODY TRUE
J 2
(5475 4875);
DISPLAY 0.872340 (5475 4875);
PAINT PEACH (5475 4875);
DISPLAY INVISIBLE (5475 4875);
FORCEPROP 1 LAST OFFPAGE TRUE
J 2
(5100 4850);
DISPLAY 0.872340 (5100 4850);
PAINT GREEN (5100 4850);
DISPLAY INVISIBLE (5100 4850);
FORCEPROP 2 LAST CDS_LIB standard
J 0
(5425 4975);
DISPLAY INVISIBLE (5425 4975);
FORCEADD Q_RES..2
(3050 3625);
FORCEPROP 1 LAST LOCATION R281
J 0
(3095 3750);
DISPLAY 0.489362 (3095 3750);
PAINT SKYBLUE (3095 3750);
FORCEPROP 0 LAST $SEC 1
J 0
(3100 3800);
DISPLAY 0.680851 (3100 3800);
PAINT MONO (3100 3800);
DISPLAY INVISIBLE (3100 3800);
FORCEPROP 0 LAST CDS_SEC 1
J 0
(3100 3800);
DISPLAY 1.021277 (3100 3800);
DISPLAY INVISIBLE (3100 3800);
FORCEPROP 1 LASTPIN (3050 3725) $PN 1
J 0
(3055 3687);
DISPLAY 0.489362 (3055 3687);
PAINT MONO (3055 3687);
FORCEPROP 1 LASTPIN (3050 3525) $PN 2
J 0
(3055 3535);
DISPLAY 0.489362 (3055 3535);
PAINT MONO (3055 3535);
FORCEPROP 1 LAST WATTAGE 1/16W
J 0
(3090 3600);
DISPLAY 0.489362 (3090 3600);
PAINT SKYBLUE (3090 3600);
FORCEPROP 1 LAST MATERIAL CHIP
J 0
(3090 3550);
DISPLAY 0.489362 (3090 3550);
PAINT SKYBLUE (3090 3550);
FORCEPROP 1 LAST TOLERANCE 5%
J 0
(3095 3650);
DISPLAY 0.489362 (3095 3650);
PAINT SKYBLUE (3095 3650);
FORCEPROP 1 LAST VALUE 1K
J 0
(3095 3700);
DISPLAY 0.489362 (3095 3700);
PAINT SKYBLUE (3095 3700);
FORCEPROP 1 LAST PACK_TYPE 0402LF
J 0
(3090 3500);
DISPLAY 0.489362 (3090 3500);
PAINT SKYBLUE (3090 3500);
FORCEPROP 2 LAST CDS_LIB pure_quanta
J 0
(3050 3625);
DISPLAY INVISIBLE (3050 3625);
FORCEPROP 1 LAST PATH I466
J 0
(3100 3800);
DISPLAY 0.978723 (3100 3800);
PAINT WHITE (3100 3800);
DISPLAY INVISIBLE (3100 3800);
FORCEPROP 1 LAST PART_NUMBER TMP_QCS21002JB34
J 0
(3090 3450);
DISPLAY 0.638298 (3090 3450);
PAINT SKYBLUE (3090 3450);
DISPLAY INVISIBLE (3090 3450);
FORCEADD OFFPAGE..2
(3900 3475);
FORCEPROP 2 LAST $XR0 110 
J 0
(4089 3475);
DISPLAY 0.638298 (4089 3475);
PAINT MONO (4089 3475);
FORCEPROP 1 LAST COMMENT_BODY TRUE
J 0
(3855 3380);
DISPLAY 0.872340 (3855 3380);
PAINT GREEN (3855 3380);
DISPLAY INVISIBLE (3855 3380);
FORCEPROP 1 LAST OFFPAGE TRUE
J 0
(4225 3350);
DISPLAY 0.723404 (4225 3350);
PAINT GREEN (4225 3350);
DISPLAY INVISIBLE (4225 3350);
FORCEPROP 2 LAST PATH I467
J 0
(4075 3550);
DISPLAY 1.021277 (4075 3550);
DISPLAY INVISIBLE (4075 3550);
FORCEPROP 2 LAST CDS_LIB standard
J 0
(3900 3475);
DISPLAY INVISIBLE (3900 3475);
FORCEADD OFFPAGE..2
(3900 3375);
FORCEPROP 2 LAST $XR0 110 
J 0
(4089 3375);
DISPLAY 0.638298 (4089 3375);
PAINT MONO (4089 3375);
FORCEPROP 1 LAST COMMENT_BODY TRUE
J 0
(3855 3280);
DISPLAY 0.872340 (3855 3280);
PAINT GREEN (3855 3280);
DISPLAY INVISIBLE (3855 3280);
FORCEPROP 1 LAST OFFPAGE TRUE
J 0
(4225 3250);
DISPLAY 0.723404 (4225 3250);
PAINT GREEN (4225 3250);
DISPLAY INVISIBLE (4225 3250);
FORCEPROP 2 LAST PATH I468
J 0
(4075 3450);
DISPLAY 1.021277 (4075 3450);
DISPLAY INVISIBLE (4075 3450);
FORCEPROP 2 LAST CDS_LIB standard
J 0
(3900 3375);
DISPLAY INVISIBLE (3900 3375);
FORCEADD Q_RES..1
(6250 1800);
FORCEPROP 1 LAST LOCATION R597
J 0
(6050 1800);
DISPLAY 0.489362 (6050 1800);
PAINT SKYBLUE (6050 1800);
FORCEPROP 0 LAST $SEC 1
J 0
(6125 1850);
DISPLAY 0.680851 (6125 1850);
PAINT MONO (6125 1850);
DISPLAY INVISIBLE (6125 1850);
FORCEPROP 0 LAST CDS_SEC 1
J 0
(6125 1850);
DISPLAY 1.021277 (6125 1850);
DISPLAY INVISIBLE (6125 1850);
FORCEPROP 1 LASTPIN (6150 1800) $PN 1
J 0
(6162 1812);
DISPLAY 0.489362 (6162 1812);
PAINT MONO (6162 1812);
FORCEPROP 1 LASTPIN (6350 1800) $PN 2
J 0
(6312 1812);
DISPLAY 0.489362 (6312 1812);
PAINT MONO (6312 1812);
FORCEPROP 1 LAST VALUE 0
J 2
(6375 1800);
DISPLAY 0.489362 (6375 1800);
PAINT SKYBLUE (6375 1800);
FORCEPROP 2 LAST CDS_LIB pure_quanta
J 0
(6250 1800);
DISPLAY INVISIBLE (6250 1800);
FORCEPROP 1 LAST PATH I469
J 0
(6200 1950);
DISPLAY 0.978723 (6200 1950);
PAINT WHITE (6200 1950);
DISPLAY INVISIBLE (6200 1950);
FORCEPROP 1 LAST WATTAGE 1/16W
J 2
(6650 1725);
DISPLAY 0.489362 (6650 1725);
PAINT SKYBLUE (6650 1725);
DISPLAY INVISIBLE (6650 1725);
FORCEPROP 1 LAST MATERIAL CHIP
J 0
(6675 1725);
DISPLAY 0.489362 (6675 1725);
PAINT SKYBLUE (6675 1725);
DISPLAY INVISIBLE (6675 1725);
FORCEPROP 1 LAST TOLERANCE 5%
J 0
(6225 1725);
DISPLAY 0.489362 (6225 1725);
PAINT SKYBLUE (6225 1725);
DISPLAY INVISIBLE (6225 1725);
FORCEPROP 1 LAST PART_NUMBER CS00002JB38
J 0
(6275 1850);
DISPLAY 0.489362 (6275 1850);
PAINT SKYBLUE (6275 1850);
DISPLAY INVISIBLE (6275 1850);
FORCEPROP 1 LAST PACK_TYPE 0402LF
J 0
(6300 1725);
DISPLAY 0.489362 (6300 1725);
PAINT SKYBLUE (6300 1725);
DISPLAY INVISIBLE (6300 1725);
FORCEADD Q_RES..1
(6250 1750);
FORCEPROP 1 LAST LOCATION R624
J 0
(6050 1750);
DISPLAY 0.489362 (6050 1750);
PAINT SKYBLUE (6050 1750);
FORCEPROP 0 LAST $SEC 1
J 0
(6125 1800);
DISPLAY 0.680851 (6125 1800);
PAINT MONO (6125 1800);
DISPLAY INVISIBLE (6125 1800);
FORCEPROP 0 LAST CDS_SEC 1
J 0
(6125 1800);
DISPLAY 1.021277 (6125 1800);
DISPLAY INVISIBLE (6125 1800);
FORCEPROP 1 LASTPIN (6150 1750) $PN 1
J 0
(6162 1762);
DISPLAY 0.489362 (6162 1762);
PAINT MONO (6162 1762);
FORCEPROP 1 LASTPIN (6350 1750) $PN 2
J 0
(6312 1762);
DISPLAY 0.489362 (6312 1762);
PAINT MONO (6312 1762);
FORCEPROP 1 LAST VALUE 0
J 2
(6375 1750);
DISPLAY 0.489362 (6375 1750);
PAINT SKYBLUE (6375 1750);
FORCEPROP 2 LAST CDS_LIB pure_quanta
J 0
(6250 1750);
DISPLAY INVISIBLE (6250 1750);
FORCEPROP 1 LAST PATH I470
J 0
(6200 1900);
DISPLAY 0.978723 (6200 1900);
PAINT WHITE (6200 1900);
DISPLAY INVISIBLE (6200 1900);
FORCEPROP 1 LAST WATTAGE 1/16W
J 2
(6650 1675);
DISPLAY 0.489362 (6650 1675);
PAINT SKYBLUE (6650 1675);
DISPLAY INVISIBLE (6650 1675);
FORCEPROP 1 LAST MATERIAL CHIP
J 0
(6675 1675);
DISPLAY 0.489362 (6675 1675);
PAINT SKYBLUE (6675 1675);
DISPLAY INVISIBLE (6675 1675);
FORCEPROP 1 LAST TOLERANCE 5%
J 0
(6225 1675);
DISPLAY 0.489362 (6225 1675);
PAINT SKYBLUE (6225 1675);
DISPLAY INVISIBLE (6225 1675);
FORCEPROP 1 LAST PART_NUMBER CS00002JB38
J 0
(6275 1800);
DISPLAY 0.489362 (6275 1800);
PAINT SKYBLUE (6275 1800);
DISPLAY INVISIBLE (6275 1800);
FORCEPROP 1 LAST PACK_TYPE 0402LF
J 0
(6300 1675);
DISPLAY 0.489362 (6300 1675);
PAINT SKYBLUE (6300 1675);
DISPLAY INVISIBLE (6300 1675);
FORCEADD OFFPAGE..1
(5450 1750);
FORCEPROP 2 LAST $XR1 110 
J 0
(5048 1750);
DISPLAY 0.638298 (5048 1750);
PAINT MONO (5048 1750);
FORCEPROP 2 LAST $XR0 111 
J 0
(5168 1750);
DISPLAY 0.638298 (5168 1750);
PAINT MONO (5168 1750);
FORCEPROP 1 LAST OFFPAGE TRUE
J 0
(5775 1625);
DISPLAY 0.872340 (5775 1625);
PAINT GREEN (5775 1625);
DISPLAY INVISIBLE (5775 1625);
FORCEPROP 1 LAST COMMENT_BODY TRUE
J 0
(5575 1650);
DISPLAY 0.872340 (5575 1650);
PAINT GREEN (5575 1650);
DISPLAY INVISIBLE (5575 1650);
FORCEPROP 2 LAST CDS_LIB standard
J 0
(5450 1750);
DISPLAY INVISIBLE (5450 1750);
FORCEPROP 2 LAST PATH I471
J 0
(5500 1825);
DISPLAY 1.021277 (5500 1825);
DISPLAY INVISIBLE (5500 1825);
FORCEADD OFFPAGE..3
R 2
(5450 1800);
FORCEPROP 2 LAST $XR1 111 
J 0
(5050 1800);
DISPLAY 0.638298 (5050 1800);
PAINT MONO (5050 1800);
FORCEPROP 2 LAST $XR0 110 
J 0
(5170 1800);
DISPLAY 0.638298 (5170 1800);
PAINT MONO (5170 1800);
FORCEPROP 1 LAST COMMENT_BODY TRUE
J 2
(5500 1700);
DISPLAY 0.872340 (5500 1700);
PAINT PEACH (5500 1700);
DISPLAY INVISIBLE (5500 1700);
FORCEPROP 1 LAST OFFPAGE TRUE
J 2
(5125 1675);
DISPLAY 0.872340 (5125 1675);
PAINT GREEN (5125 1675);
DISPLAY INVISIBLE (5125 1675);
FORCEPROP 2 LAST CDS_LIB standard
J 0
(5450 1800);
DISPLAY INVISIBLE (5450 1800);
FORCEPROP 2 LAST PATH I472
J 0
(5500 1875);
DISPLAY 1.021277 (5500 1875);
DISPLAY INVISIBLE (5500 1875);
FORCEADD Q_RES..1
(6225 4825);
FORCEPROP 1 LAST LOCATION R1212
J 0
(6025 4825);
DISPLAY 0.489362 (6025 4825);
PAINT SKYBLUE (6025 4825);
FORCEPROP 0 LAST $SEC 1
J 0
(6100 4875);
DISPLAY 0.680851 (6100 4875);
PAINT MONO (6100 4875);
DISPLAY INVISIBLE (6100 4875);
FORCEPROP 0 LAST CDS_SEC 1
J 0
(6100 4875);
DISPLAY 1.021277 (6100 4875);
DISPLAY INVISIBLE (6100 4875);
FORCEPROP 1 LASTPIN (6125 4825) $PN 1
J 0
(6137 4837);
DISPLAY 0.489362 (6137 4837);
PAINT MONO (6137 4837);
FORCEPROP 1 LASTPIN (6325 4825) $PN 2
J 0
(6287 4837);
DISPLAY 0.489362 (6287 4837);
PAINT MONO (6287 4837);
FORCEPROP 1 LAST VALUE 0
J 2
(6350 4825);
DISPLAY 0.489362 (6350 4825);
PAINT SKYBLUE (6350 4825);
FORCEPROP 2 LAST CDS_LIB pure_quanta
J 0
(6225 4825);
DISPLAY INVISIBLE (6225 4825);
FORCEPROP 1 LAST PATH I473
J 0
(6175 4975);
DISPLAY 0.978723 (6175 4975);
PAINT WHITE (6175 4975);
DISPLAY INVISIBLE (6175 4975);
FORCEPROP 1 LAST WATTAGE 1/16W
J 2
(6625 4750);
DISPLAY 0.489362 (6625 4750);
PAINT SKYBLUE (6625 4750);
DISPLAY INVISIBLE (6625 4750);
FORCEPROP 1 LAST MATERIAL CHIP
J 0
(6650 4750);
DISPLAY 0.489362 (6650 4750);
PAINT SKYBLUE (6650 4750);
DISPLAY INVISIBLE (6650 4750);
FORCEPROP 1 LAST TOLERANCE 5%
J 0
(6200 4750);
DISPLAY 0.489362 (6200 4750);
PAINT SKYBLUE (6200 4750);
DISPLAY INVISIBLE (6200 4750);
FORCEPROP 1 LAST PART_NUMBER CS00002JB38
J 0
(6250 4875);
DISPLAY 0.489362 (6250 4875);
PAINT SKYBLUE (6250 4875);
DISPLAY INVISIBLE (6250 4875);
FORCEPROP 1 LAST PACK_TYPE 0402LF
J 0
(6275 4750);
DISPLAY 0.489362 (6275 4750);
PAINT SKYBLUE (6275 4750);
DISPLAY INVISIBLE (6275 4750);
FORCEADD OFFPAGE..1
(5425 4825);
FORCEPROP 2 LAST $XR1 110 
J 0
(5084 4825);
DISPLAY 0.638298 (5084 4825);
PAINT MONO (5084 4825);
FORCEPROP 2 LAST $XR0 83 
J 0
(5204 4825);
DISPLAY 0.638298 (5204 4825);
PAINT MONO (5204 4825);
FORCEPROP 2 LAST CDS_LIB standard
J 0
(5425 4825);
DISPLAY INVISIBLE (5425 4825);
FORCEPROP 1 LAST OFFPAGE TRUE
J 0
(5750 4700);
DISPLAY 0.872340 (5750 4700);
PAINT GREEN (5750 4700);
DISPLAY INVISIBLE (5750 4700);
FORCEPROP 1 LAST COMMENT_BODY TRUE
J 0
(5550 4725);
DISPLAY 0.872340 (5550 4725);
PAINT GREEN (5550 4725);
DISPLAY INVISIBLE (5550 4725);
FORCEPROP 2 LAST PATH I474
J 0
(5475 4900);
DISPLAY 0.680851 (5475 4900);
DISPLAY INVISIBLE (5475 4900);
FORCEADD Q_RES..1
(6250 1650);
FORCEPROP 1 LAST LOCATION R1213
J 0
(6050 1650);
DISPLAY 0.489362 (6050 1650);
PAINT SKYBLUE (6050 1650);
FORCEPROP 0 LAST $SEC 1
J 0
(6125 1700);
DISPLAY 0.680851 (6125 1700);
PAINT MONO (6125 1700);
DISPLAY INVISIBLE (6125 1700);
FORCEPROP 0 LAST CDS_SEC 1
J 0
(6125 1700);
DISPLAY 1.021277 (6125 1700);
DISPLAY INVISIBLE (6125 1700);
FORCEPROP 1 LASTPIN (6150 1650) $PN 1
J 0
(6162 1662);
DISPLAY 0.489362 (6162 1662);
PAINT MONO (6162 1662);
FORCEPROP 1 LASTPIN (6350 1650) $PN 2
J 0
(6312 1662);
DISPLAY 0.489362 (6312 1662);
PAINT MONO (6312 1662);
FORCEPROP 1 LAST VALUE 0
J 2
(6375 1650);
DISPLAY 0.489362 (6375 1650);
PAINT SKYBLUE (6375 1650);
FORCEPROP 2 LAST CDS_LIB pure_quanta
J 0
(6250 1650);
DISPLAY INVISIBLE (6250 1650);
FORCEPROP 1 LAST PATH I475
J 0
(6200 1800);
DISPLAY 0.978723 (6200 1800);
PAINT WHITE (6200 1800);
DISPLAY INVISIBLE (6200 1800);
FORCEPROP 1 LAST WATTAGE 1/16W
J 2
(6650 1575);
DISPLAY 0.489362 (6650 1575);
PAINT SKYBLUE (6650 1575);
DISPLAY INVISIBLE (6650 1575);
FORCEPROP 1 LAST MATERIAL CHIP
J 0
(6675 1575);
DISPLAY 0.489362 (6675 1575);
PAINT SKYBLUE (6675 1575);
DISPLAY INVISIBLE (6675 1575);
FORCEPROP 1 LAST TOLERANCE 5%
J 0
(6225 1575);
DISPLAY 0.489362 (6225 1575);
PAINT SKYBLUE (6225 1575);
DISPLAY INVISIBLE (6225 1575);
FORCEPROP 1 LAST PART_NUMBER CS00002JB38
J 0
(6275 1700);
DISPLAY 0.489362 (6275 1700);
PAINT SKYBLUE (6275 1700);
DISPLAY INVISIBLE (6275 1700);
FORCEPROP 1 LAST PACK_TYPE 0402LF
J 0
(6300 1575);
DISPLAY 0.489362 (6300 1575);
PAINT SKYBLUE (6300 1575);
DISPLAY INVISIBLE (6300 1575);
FORCEADD OFFPAGE..1
(5450 1650);
FORCEPROP 2 LAST $XR1 110 
J 0
(5109 1650);
DISPLAY 0.638298 (5109 1650);
PAINT MONO (5109 1650);
FORCEPROP 2 LAST $XR0 83 
J 0
(5229 1650);
DISPLAY 0.638298 (5229 1650);
PAINT MONO (5229 1650);
FORCEPROP 2 LAST PATH I476
J 0
(5500 1725);
DISPLAY 0.680851 (5500 1725);
DISPLAY INVISIBLE (5500 1725);
FORCEPROP 1 LAST COMMENT_BODY TRUE
J 0
(5575 1550);
DISPLAY 0.872340 (5575 1550);
PAINT GREEN (5575 1550);
DISPLAY INVISIBLE (5575 1550);
FORCEPROP 1 LAST OFFPAGE TRUE
J 0
(5775 1525);
DISPLAY 0.872340 (5775 1525);
PAINT GREEN (5775 1525);
DISPLAY INVISIBLE (5775 1525);
FORCEPROP 2 LAST CDS_LIB standard
J 0
(5450 1650);
DISPLAY INVISIBLE (5450 1650);
FORCEADD Q_RES..2
(4550 3675);
FORCEPROP 1 LAST LOCATION R949
J 0
(4595 3800);
DISPLAY 0.489362 (4595 3800);
PAINT SKYBLUE (4595 3800);
FORCEPROP 2 LAST $SEC 1
J 0
(4600 3900);
DISPLAY 0.680851 (4600 3900);
PAINT MONO (4600 3900);
DISPLAY INVISIBLE (4600 3900);
FORCEPROP 2 LAST CDS_SEC 1
J 0
(4600 3900);
DISPLAY 1.021277 (4600 3900);
DISPLAY INVISIBLE (4600 3900);
FORCEPROP 1 LASTPIN (4550 3775) $PN 1
J 0
(4555 3737);
DISPLAY 0.489362 (4555 3737);
FORCEPROP 1 LASTPIN (4550 3575) $PN 2
J 0
(4555 3585);
DISPLAY 0.489362 (4555 3585);
FORCEPROP 1 LAST WATTAGE 1/16W
J 0
(4590 3650);
DISPLAY 0.489362 (4590 3650);
PAINT SKYBLUE (4590 3650);
FORCEPROP 1 LAST MATERIAL EMPTY
J 0
(4590 3600);
DISPLAY 0.489362 (4590 3600);
PAINT RED (4590 3600);
FORCEPROP 1 LAST TOLERANCE 1%
J 0
(4595 3700);
DISPLAY 0.489362 (4595 3700);
PAINT SKYBLUE (4595 3700);
FORCEPROP 1 LAST VALUE 4.7K
J 0
(4595 3750);
DISPLAY 0.489362 (4595 3750);
PAINT SKYBLUE (4595 3750);
FORCEPROP 1 LAST PACK_TYPE 0402LF
J 0
(4600 3550);
DISPLAY 0.489362 (4600 3550);
PAINT SKYBLUE (4600 3550);
FORCEPROP 2 LAST CDS_LIB pure_quanta
J 0
(4550 3675);
PAINT MONO (4550 3675);
DISPLAY INVISIBLE (4550 3675);
FORCEPROP 1 LAST PATH I477
J 0
(4600 3850);
DISPLAY 0.978723 (4600 3850);
PAINT WHITE (4600 3850);
DISPLAY INVISIBLE (4600 3850);
FORCEPROP 1 LAST PART_NUMBER CS24702FB10
J 0
(4590 3550);
DISPLAY 0.617021 (4590 3550);
PAINT SKYBLUE (4590 3550);
DISPLAY INVISIBLE (4590 3550);
FORCEADD Q_RES..2
(4550 3275);
FORCEPROP 1 LAST LOCATION R1209
J 0
(4595 3400);
DISPLAY 0.489362 (4595 3400);
PAINT SKYBLUE (4595 3400);
FORCEPROP 2 LAST $SEC 1
J 0
(4600 3500);
DISPLAY 0.680851 (4600 3500);
PAINT MONO (4600 3500);
DISPLAY INVISIBLE (4600 3500);
FORCEPROP 2 LAST CDS_SEC 1
J 0
(4600 3500);
DISPLAY 1.021277 (4600 3500);
DISPLAY INVISIBLE (4600 3500);
FORCEPROP 1 LASTPIN (4550 3375) $PN 1
J 0
(4555 3337);
DISPLAY 0.489362 (4555 3337);
FORCEPROP 1 LASTPIN (4550 3175) $PN 2
J 0
(4555 3185);
DISPLAY 0.489362 (4555 3185);
FORCEPROP 1 LAST WATTAGE 1/16W
J 0
(4590 3250);
DISPLAY 0.489362 (4590 3250);
PAINT SKYBLUE (4590 3250);
FORCEPROP 1 LAST MATERIAL EMPTY
J 0
(4590 3200);
DISPLAY 0.489362 (4590 3200);
PAINT RED (4590 3200);
FORCEPROP 1 LAST TOLERANCE 1%
J 0
(4595 3300);
DISPLAY 0.489362 (4595 3300);
PAINT SKYBLUE (4595 3300);
FORCEPROP 1 LAST VALUE 4.7K
J 0
(4595 3350);
DISPLAY 0.489362 (4595 3350);
PAINT SKYBLUE (4595 3350);
FORCEPROP 1 LAST PACK_TYPE 0402LF
J 0
(4600 3150);
DISPLAY 0.489362 (4600 3150);
PAINT SKYBLUE (4600 3150);
FORCEPROP 2 LAST CDS_LIB pure_quanta
J 0
(4550 3275);
PAINT MONO (4550 3275);
DISPLAY INVISIBLE (4550 3275);
FORCEPROP 1 LAST PATH I478
J 0
(4600 3450);
DISPLAY 0.978723 (4600 3450);
PAINT WHITE (4600 3450);
DISPLAY INVISIBLE (4600 3450);
FORCEPROP 1 LAST PART_NUMBER CS24702FB10
J 0
(4590 3150);
DISPLAY 0.617021 (4590 3150);
PAINT SKYBLUE (4590 3150);
DISPLAY INVISIBLE (4590 3150);
FORCEADD UNIVERSAL_POWER..1
(4550 3925);
FORCEPROP 3 LASTPIN (4550 3875) SIG_NAME P3V3\g
J 0
(4560 3885);
DISPLAY 0.659574 (4560 3885);
PAINT MONO (4560 3885);
DISPLAY INVISIBLE (4560 3885);
FORCEPROP 1 LAST HDL_POWER P3V3
J 1
(4550 3975);
DISPLAY 0.489362 (4550 3975);
PAINT GREEN (4550 3975);
FORCEPROP 2 LAST CDS_LIB pure_quanta_power
J 0
(4550 3925);
DISPLAY INVISIBLE (4550 3925);
FORCEPROP 1 LAST PATH I479
J 0
(4600 3950);
DISPLAY 0.872340 (4600 3950);
PAINT AQUA (4600 3950);
DISPLAY INVISIBLE (4600 3950);
FORCEADD UNIVERSAL_GND..1
(4550 3025);
FORCEPROP 3 LASTPIN (4550 3075) SIG_NAME GND\g
J 0
(4560 3085);
DISPLAY 0.659574 (4560 3085);
PAINT MONO (4560 3085);
DISPLAY INVISIBLE (4560 3085);
FORCEPROP 2 LAST CDS_LIB pure_quanta_power
J 0
(4550 3025);
DISPLAY INVISIBLE (4550 3025);
FORCEPROP 1 LAST PATH I480
J 0
(4625 3025);
DISPLAY 0.872340 (4625 3025);
PAINT AQUA (4625 3025);
DISPLAY INVISIBLE (4625 3025);
FORCEPROP 1 LAST HDL_POWER GND
J 1
(4575 2950);
DISPLAY 0.872340 (4575 2950);
PAINT GREEN (4575 2950);
DISPLAY INVISIBLE (4575 2950);
FORCEADD Q_RES..2
(4800 3675);
FORCEPROP 1 LAST LOCATION R1210
J 0
(4845 3800);
DISPLAY 0.489362 (4845 3800);
PAINT SKYBLUE (4845 3800);
FORCEPROP 2 LAST $SEC 1
J 0
(4850 3900);
DISPLAY 0.680851 (4850 3900);
PAINT MONO (4850 3900);
DISPLAY INVISIBLE (4850 3900);
FORCEPROP 2 LAST CDS_SEC 1
J 0
(4850 3900);
DISPLAY 0.680851 (4850 3900);
DISPLAY INVISIBLE (4850 3900);
FORCEPROP 1 LASTPIN (4800 3775) $PN 1
J 0
(4805 3737);
DISPLAY 0.489362 (4805 3737);
PAINT MONO (4805 3737);
FORCEPROP 1 LASTPIN (4800 3575) $PN 2
J 0
(4805 3585);
DISPLAY 0.489362 (4805 3585);
PAINT MONO (4805 3585);
FORCEPROP 1 LAST WATTAGE 1/16W
J 0
(4840 3650);
DISPLAY 0.489362 (4840 3650);
PAINT SKYBLUE (4840 3650);
FORCEPROP 1 LAST MATERIAL EMPTY
J 0
(4840 3600);
DISPLAY 0.489362 (4840 3600);
PAINT RED (4840 3600);
FORCEPROP 1 LAST TOLERANCE 1%
J 0
(4845 3700);
DISPLAY 0.489362 (4845 3700);
PAINT SKYBLUE (4845 3700);
FORCEPROP 1 LAST VALUE 4.7K
J 0
(4845 3750);
DISPLAY 0.489362 (4845 3750);
PAINT SKYBLUE (4845 3750);
FORCEPROP 1 LAST PACK_TYPE 0402LF
J 0
(4850 3550);
DISPLAY 0.489362 (4850 3550);
PAINT SKYBLUE (4850 3550);
FORCEPROP 2 LAST CDS_LIB pure_quanta
J 0
(4800 3675);
DISPLAY INVISIBLE (4800 3675);
FORCEPROP 1 LAST PATH I481
J 0
(4850 3850);
DISPLAY 0.978723 (4850 3850);
PAINT WHITE (4850 3850);
DISPLAY INVISIBLE (4850 3850);
FORCEPROP 1 LAST PART_NUMBER CS24702FB10
J 0
(4840 3550);
DISPLAY 0.617021 (4840 3550);
PAINT SKYBLUE (4840 3550);
DISPLAY INVISIBLE (4840 3550);
FORCEADD Q_RES..2
(4800 3275);
FORCEPROP 1 LAST LOCATION R1211
J 0
(4850 3400);
DISPLAY 0.489362 (4850 3400);
PAINT SKYBLUE (4850 3400);
FORCEPROP 2 LAST $SEC 1
J 0
(4850 3500);
DISPLAY 0.680851 (4850 3500);
PAINT MONO (4850 3500);
DISPLAY INVISIBLE (4850 3500);
FORCEPROP 2 LAST CDS_SEC 1
J 0
(4850 3500);
DISPLAY 0.680851 (4850 3500);
DISPLAY INVISIBLE (4850 3500);
FORCEPROP 1 LASTPIN (4800 3375) $PN 1
J 0
(4805 3337);
DISPLAY 0.489362 (4805 3337);
PAINT MONO (4805 3337);
FORCEPROP 1 LASTPIN (4800 3175) $PN 2
J 0
(4805 3185);
DISPLAY 0.489362 (4805 3185);
PAINT MONO (4805 3185);
FORCEPROP 1 LAST WATTAGE 1/16W
J 0
(4840 3250);
DISPLAY 0.489362 (4840 3250);
PAINT SKYBLUE (4840 3250);
FORCEPROP 1 LAST MATERIAL EMPTY
J 0
(4840 3200);
DISPLAY 0.489362 (4840 3200);
PAINT RED (4840 3200);
FORCEPROP 1 LAST TOLERANCE 1%
J 0
(4845 3300);
DISPLAY 0.489362 (4845 3300);
PAINT SKYBLUE (4845 3300);
FORCEPROP 1 LAST VALUE 4.7K
J 0
(4845 3350);
DISPLAY 0.489362 (4845 3350);
PAINT SKYBLUE (4845 3350);
FORCEPROP 1 LAST PACK_TYPE 0402LF
J 0
(4850 3150);
DISPLAY 0.489362 (4850 3150);
PAINT SKYBLUE (4850 3150);
FORCEPROP 2 LAST CDS_LIB pure_quanta
J 0
(4800 3275);
DISPLAY INVISIBLE (4800 3275);
FORCEPROP 1 LAST PATH I482
J 0
(4850 3450);
DISPLAY 0.978723 (4850 3450);
PAINT WHITE (4850 3450);
DISPLAY INVISIBLE (4850 3450);
FORCEPROP 1 LAST PART_NUMBER CS24702FB10
J 0
(4840 3150);
DISPLAY 0.617021 (4840 3150);
PAINT SKYBLUE (4840 3150);
DISPLAY INVISIBLE (4840 3150);
FORCEADD OFFPAGE..2
(5750 3425);
FORCEPROP 2 LAST $XR1 110 
J 0
(6029 3425);
DISPLAY 0.638298 (6029 3425);
PAINT MONO (6029 3425);
FORCEPROP 2 LAST $XR0 83 
J 0
(5939 3425);
DISPLAY 0.638298 (5939 3425);
PAINT MONO (5939 3425);
FORCEPROP 1 LAST COMMENT_BODY TRUE
J 0
(5705 3330);
DISPLAY 0.872340 (5705 3330);
PAINT GREEN (5705 3330);
DISPLAY INVISIBLE (5705 3330);
FORCEPROP 1 LAST OFFPAGE TRUE
J 0
(6075 3300);
DISPLAY 0.723404 (6075 3300);
PAINT GREEN (6075 3300);
DISPLAY INVISIBLE (6075 3300);
FORCEPROP 2 LAST PATH I483
J 0
(5925 3500);
DISPLAY 0.680851 (5925 3500);
DISPLAY INVISIBLE (5925 3500);
FORCEPROP 2 LAST CDS_LIB standard
J 0
(5750 3425);
DISPLAY INVISIBLE (5750 3425);
FORCEADD OFFPAGE..2
(5750 3500);
FORCEPROP 2 LAST $XR1 110 
J 0
(6029 3500);
DISPLAY 0.638298 (6029 3500);
PAINT MONO (6029 3500);
FORCEPROP 2 LAST $XR0 83 
J 0
(5939 3500);
DISPLAY 0.638298 (5939 3500);
PAINT MONO (5939 3500);
FORCEPROP 2 LAST CDS_LIB standard
J 0
(5750 3500);
DISPLAY INVISIBLE (5750 3500);
FORCEPROP 2 LAST PATH I484
J 0
(5925 3575);
DISPLAY 0.680851 (5925 3575);
DISPLAY INVISIBLE (5925 3575);
FORCEPROP 1 LAST OFFPAGE TRUE
J 0
(6075 3375);
DISPLAY 0.723404 (6075 3375);
PAINT GREEN (6075 3375);
DISPLAY INVISIBLE (6075 3375);
FORCEPROP 1 LAST COMMENT_BODY TRUE
J 0
(5705 3405);
DISPLAY 0.872340 (5705 3405);
PAINT GREEN (5705 3405);
DISPLAY INVISIBLE (5705 3405);
FORCEADD UNIVERSAL_GND..1
(9675 4025);
FORCEPROP 3 LASTPIN (9675 4075) SIG_NAME GND\g
J 0
(9685 4085);
DISPLAY 0.659574 (9685 4085);
PAINT MONO (9685 4085);
DISPLAY INVISIBLE (9685 4085);
FORCEPROP 1 LAST HDL_POWER GND
J 1
(9700 3950);
DISPLAY 0.489362 (9700 3950);
PAINT GREEN (9700 3950);
FORCEPROP 2 LAST CDS_LIB pure_quanta_power
J 0
(9675 4025);
DISPLAY INVISIBLE (9675 4025);
FORCEPROP 1 LAST PATH I497
J 0
(9750 4025);
DISPLAY 0.872340 (9750 4025);
PAINT AQUA (9750 4025);
DISPLAY INVISIBLE (9750 4025);
FORCEADD OFFPAGE..4
(10300 1550);
FORCEPROP 2 LAST $XR0 79 
J 0
(10486 1550);
DISPLAY 0.638298 (10486 1550);
PAINT MONO (10486 1550);
FORCEPROP 1 LAST OFFPAGE TRUE
J 0
(10625 1425);
DISPLAY 0.872340 (10625 1425);
PAINT GREEN (10625 1425);
DISPLAY INVISIBLE (10625 1425);
FORCEPROP 1 LAST COMMENT_BODY TRUE
J 0
(10275 1450);
DISPLAY 0.872340 (10275 1450);
PAINT GREEN (10275 1450);
DISPLAY INVISIBLE (10275 1450);
FORCEPROP 2 LAST CDS_LIB standard
J 0
(10300 1550);
DISPLAY INVISIBLE (10300 1550);
FORCEPROP 2 LAST PATH I498
J 0
(10475 1625);
DISPLAY 0.680851 (10475 1625);
DISPLAY INVISIBLE (10475 1625);
FORCEADD OFFPAGE..4
(10300 1500);
FORCEPROP 2 LAST $XR0 79 
J 0
(10486 1500);
DISPLAY 0.638298 (10486 1500);
PAINT MONO (10486 1500);
FORCEPROP 2 LAST CDS_LIB standard
J 0
(10300 1500);
DISPLAY INVISIBLE (10300 1500);
FORCEPROP 1 LAST COMMENT_BODY TRUE
J 0
(10275 1400);
DISPLAY 0.872340 (10275 1400);
PAINT GREEN (10275 1400);
DISPLAY INVISIBLE (10275 1400);
FORCEPROP 1 LAST OFFPAGE TRUE
J 0
(10625 1375);
DISPLAY 0.872340 (10625 1375);
PAINT GREEN (10625 1375);
DISPLAY INVISIBLE (10625 1375);
FORCEPROP 2 LAST PATH I499
J 0
(10475 1575);
DISPLAY 0.680851 (10475 1575);
DISPLAY INVISIBLE (10475 1575);
FORCEADD OFFPAGE..4
(10300 1600);
FORCEPROP 2 LAST $XR0 79 
J 0
(10486 1600);
DISPLAY 0.638298 (10486 1600);
PAINT MONO (10486 1600);
FORCEPROP 1 LAST OFFPAGE TRUE
J 0
(10625 1475);
DISPLAY 0.872340 (10625 1475);
PAINT GREEN (10625 1475);
DISPLAY INVISIBLE (10625 1475);
FORCEPROP 1 LAST COMMENT_BODY TRUE
J 0
(10275 1500);
DISPLAY 0.872340 (10275 1500);
PAINT GREEN (10275 1500);
DISPLAY INVISIBLE (10275 1500);
FORCEPROP 2 LAST CDS_LIB standard
J 0
(10300 1600);
DISPLAY INVISIBLE (10300 1600);
FORCEPROP 2 LAST PATH I500
J 0
(10475 1675);
DISPLAY 0.680851 (10475 1675);
DISPLAY INVISIBLE (10475 1675);
FORCEADD UNIVERSAL_GND..1
(9575 875);
FORCEPROP 3 LASTPIN (9575 925) SIG_NAME GND\g
J 0
(9585 935);
DISPLAY 0.659574 (9585 935);
PAINT MONO (9585 935);
DISPLAY INVISIBLE (9585 935);
FORCEPROP 1 LAST HDL_POWER GND
J 1
(9600 800);
DISPLAY 0.489362 (9600 800);
PAINT GREEN (9600 800);
FORCEPROP 2 LAST CDS_LIB pure_quanta_power
J 0
(9575 875);
DISPLAY INVISIBLE (9575 875);
FORCEPROP 1 LAST PATH I504
J 0
(9650 875);
DISPLAY 0.872340 (9650 875);
PAINT AQUA (9650 875);
DISPLAY INVISIBLE (9650 875);
FORCEADD OFFPAGE..4
(10300 1450);
FORCEPROP 2 LAST $XR0 79 
J 0
(10486 1450);
DISPLAY 0.638298 (10486 1450);
PAINT MONO (10486 1450);
FORCEPROP 1 LAST OFFPAGE TRUE
J 0
(10625 1325);
DISPLAY 0.872340 (10625 1325);
PAINT GREEN (10625 1325);
DISPLAY INVISIBLE (10625 1325);
FORCEPROP 1 LAST COMMENT_BODY TRUE
J 0
(10275 1350);
DISPLAY 0.872340 (10275 1350);
PAINT GREEN (10275 1350);
DISPLAY INVISIBLE (10275 1350);
FORCEPROP 2 LAST CDS_LIB standard
J 0
(10300 1450);
DISPLAY INVISIBLE (10300 1450);
FORCEPROP 2 LAST PATH I508
J 0
(10475 1525);
DISPLAY 0.680851 (10475 1525);
DISPLAY INVISIBLE (10475 1525);
FORCEADD Q_RES..1
(9350 1250);
FORCEPROP 1 LAST LOCATION R1218
J 0
(9250 1250);
DISPLAY 0.489362 (9250 1250);
PAINT SKYBLUE (9250 1250);
FORCEPROP 2 LAST $SEC 1
J 0
(9300 1450);
DISPLAY 0.680851 (9300 1450);
PAINT MONO (9300 1450);
DISPLAY INVISIBLE (9300 1450);
FORCEPROP 2 LAST CDS_SEC 1
J 0
(9300 1450);
DISPLAY 0.680851 (9300 1450);
DISPLAY INVISIBLE (9300 1450);
FORCEPROP 1 LASTPIN (9250 1250) $PN 1
J 0
(9262 1262);
DISPLAY 0.489362 (9262 1262);
PAINT MONO (9262 1262);
FORCEPROP 1 LASTPIN (9450 1250) $PN 2
J 0
(9412 1262);
DISPLAY 0.489362 (9412 1262);
PAINT MONO (9412 1262);
FORCEPROP 1 LAST MATERIAL EMPTY
J 0
(9500 1250);
DISPLAY 0.489362 (9500 1250);
PAINT RED (9500 1250);
FORCEPROP 1 LAST VALUE 100
J 2
(9475 1250);
DISPLAY 0.489362 (9475 1250);
PAINT SKYBLUE (9475 1250);
FORCEPROP 2 LAST CDS_LIB pure_quanta
J 0
(9350 1250);
DISPLAY INVISIBLE (9350 1250);
FORCEPROP 1 LAST PATH I510
J 0
(9300 1400);
DISPLAY 0.978723 (9300 1400);
PAINT WHITE (9300 1400);
DISPLAY INVISIBLE (9300 1400);
FORCEPROP 1 LAST WATTAGE 1/16W
J 2
(9325 1100);
DISPLAY 0.978723 (9325 1100);
PAINT SKYBLUE (9325 1100);
DISPLAY INVISIBLE (9325 1100);
FORCEPROP 1 LAST TOLERANCE 1%
J 0
(9350 1150);
DISPLAY 0.978723 (9350 1150);
PAINT SKYBLUE (9350 1150);
DISPLAY INVISIBLE (9350 1150);
FORCEPROP 1 LAST PART_NUMBER TMP_QCS11002FB22
J 0
(9300 1350);
DISPLAY 0.978723 (9300 1350);
PAINT SKYBLUE (9300 1350);
DISPLAY INVISIBLE (9300 1350);
FORCEPROP 1 LAST PACK_TYPE 0402LF
J 0
(9600 1100);
DISPLAY 0.978723 (9600 1100);
PAINT SKYBLUE (9600 1100);
DISPLAY INVISIBLE (9600 1100);
FORCEADD Q_RES..1
(9350 1150);
FORCEPROP 1 LAST LOCATION R1219
J 0
(9250 1150);
DISPLAY 0.489362 (9250 1150);
PAINT SKYBLUE (9250 1150);
FORCEPROP 2 LAST $SEC 1
J 0
(9300 1350);
DISPLAY 0.680851 (9300 1350);
PAINT MONO (9300 1350);
DISPLAY INVISIBLE (9300 1350);
FORCEPROP 2 LAST CDS_SEC 1
J 0
(9300 1350);
DISPLAY 0.680851 (9300 1350);
DISPLAY INVISIBLE (9300 1350);
FORCEPROP 1 LASTPIN (9250 1150) $PN 1
J 0
(9262 1162);
DISPLAY 0.489362 (9262 1162);
PAINT MONO (9262 1162);
FORCEPROP 1 LASTPIN (9450 1150) $PN 2
J 0
(9412 1162);
DISPLAY 0.489362 (9412 1162);
PAINT MONO (9412 1162);
FORCEPROP 1 LAST MATERIAL EMPTY
J 0
(9500 1150);
DISPLAY 0.489362 (9500 1150);
PAINT RED (9500 1150);
FORCEPROP 1 LAST VALUE 100
J 2
(9475 1150);
DISPLAY 0.489362 (9475 1150);
PAINT SKYBLUE (9475 1150);
FORCEPROP 2 LAST CDS_LIB pure_quanta
J 0
(9350 1150);
DISPLAY INVISIBLE (9350 1150);
FORCEPROP 1 LAST PATH I511
J 0
(9300 1300);
DISPLAY 0.978723 (9300 1300);
PAINT WHITE (9300 1300);
DISPLAY INVISIBLE (9300 1300);
FORCEPROP 1 LAST WATTAGE 1/16W
J 2
(9325 1000);
DISPLAY 0.978723 (9325 1000);
PAINT SKYBLUE (9325 1000);
DISPLAY INVISIBLE (9325 1000);
FORCEPROP 1 LAST TOLERANCE 1%
J 0
(9350 1050);
DISPLAY 0.978723 (9350 1050);
PAINT SKYBLUE (9350 1050);
DISPLAY INVISIBLE (9350 1050);
FORCEPROP 1 LAST PART_NUMBER TMP_QCS11002FB22
J 0
(9300 1250);
DISPLAY 0.978723 (9300 1250);
PAINT SKYBLUE (9300 1250);
DISPLAY INVISIBLE (9300 1250);
FORCEPROP 1 LAST PACK_TYPE 0402LF
J 0
(9600 1000);
DISPLAY 0.978723 (9600 1000);
PAINT SKYBLUE (9600 1000);
DISPLAY INVISIBLE (9600 1000);
FORCEADD Q_RES..1
(9350 1075);
FORCEPROP 1 LAST LOCATION R1220
J 0
(9250 1075);
DISPLAY 0.489362 (9250 1075);
PAINT SKYBLUE (9250 1075);
FORCEPROP 2 LAST $SEC 1
J 0
(9300 1275);
DISPLAY 0.680851 (9300 1275);
PAINT MONO (9300 1275);
DISPLAY INVISIBLE (9300 1275);
FORCEPROP 2 LAST CDS_SEC 1
J 0
(9300 1275);
DISPLAY 0.680851 (9300 1275);
DISPLAY INVISIBLE (9300 1275);
FORCEPROP 1 LASTPIN (9250 1075) $PN 1
J 0
(9262 1087);
DISPLAY 0.489362 (9262 1087);
PAINT MONO (9262 1087);
FORCEPROP 1 LASTPIN (9450 1075) $PN 2
J 0
(9412 1087);
DISPLAY 0.489362 (9412 1087);
PAINT MONO (9412 1087);
FORCEPROP 1 LAST MATERIAL EMPTY
J 0
(9500 1075);
DISPLAY 0.489362 (9500 1075);
PAINT RED (9500 1075);
FORCEPROP 1 LAST VALUE 100
J 2
(9475 1075);
DISPLAY 0.489362 (9475 1075);
PAINT SKYBLUE (9475 1075);
FORCEPROP 2 LAST CDS_LIB pure_quanta
J 0
(9350 1075);
DISPLAY INVISIBLE (9350 1075);
FORCEPROP 1 LAST PATH I512
J 0
(9300 1225);
DISPLAY 0.978723 (9300 1225);
PAINT WHITE (9300 1225);
DISPLAY INVISIBLE (9300 1225);
FORCEPROP 1 LAST WATTAGE 1/16W
J 2
(9325 925);
DISPLAY 0.978723 (9325 925);
PAINT SKYBLUE (9325 925);
DISPLAY INVISIBLE (9325 925);
FORCEPROP 1 LAST TOLERANCE 1%
J 0
(9350 975);
DISPLAY 0.978723 (9350 975);
PAINT SKYBLUE (9350 975);
DISPLAY INVISIBLE (9350 975);
FORCEPROP 1 LAST PART_NUMBER TMP_QCS11002FB22
J 0
(9300 1175);
DISPLAY 0.978723 (9300 1175);
PAINT SKYBLUE (9300 1175);
DISPLAY INVISIBLE (9300 1175);
FORCEPROP 1 LAST PACK_TYPE 0402LF
J 0
(9600 925);
DISPLAY 0.978723 (9600 925);
PAINT SKYBLUE (9600 925);
DISPLAY INVISIBLE (9600 925);
FORCEADD Q_RES..1
(9350 975);
FORCEPROP 1 LAST LOCATION R1221
J 0
(9250 975);
DISPLAY 0.489362 (9250 975);
PAINT SKYBLUE (9250 975);
FORCEPROP 2 LAST $SEC 1
J 0
(9300 1175);
DISPLAY 0.680851 (9300 1175);
PAINT MONO (9300 1175);
DISPLAY INVISIBLE (9300 1175);
FORCEPROP 2 LAST CDS_SEC 1
J 0
(9300 1175);
DISPLAY 0.680851 (9300 1175);
DISPLAY INVISIBLE (9300 1175);
FORCEPROP 1 LASTPIN (9250 975) $PN 1
J 0
(9262 987);
DISPLAY 0.489362 (9262 987);
PAINT MONO (9262 987);
FORCEPROP 1 LASTPIN (9450 975) $PN 2
J 0
(9412 987);
DISPLAY 0.489362 (9412 987);
PAINT MONO (9412 987);
FORCEPROP 1 LAST MATERIAL EMPTY
J 0
(9500 975);
DISPLAY 0.489362 (9500 975);
PAINT RED (9500 975);
FORCEPROP 1 LAST VALUE 100
J 2
(9475 975);
DISPLAY 0.489362 (9475 975);
PAINT SKYBLUE (9475 975);
FORCEPROP 2 LAST CDS_LIB pure_quanta
J 0
(9350 975);
DISPLAY INVISIBLE (9350 975);
FORCEPROP 1 LAST PATH I513
J 0
(9300 1125);
DISPLAY 0.978723 (9300 1125);
PAINT WHITE (9300 1125);
DISPLAY INVISIBLE (9300 1125);
FORCEPROP 1 LAST WATTAGE 1/16W
J 2
(9325 825);
DISPLAY 0.978723 (9325 825);
PAINT SKYBLUE (9325 825);
DISPLAY INVISIBLE (9325 825);
FORCEPROP 1 LAST TOLERANCE 1%
J 0
(9350 875);
DISPLAY 0.978723 (9350 875);
PAINT SKYBLUE (9350 875);
DISPLAY INVISIBLE (9350 875);
FORCEPROP 1 LAST PART_NUMBER TMP_QCS11002FB22
J 0
(9300 1075);
DISPLAY 0.978723 (9300 1075);
PAINT SKYBLUE (9300 1075);
DISPLAY INVISIBLE (9300 1075);
FORCEPROP 1 LAST PACK_TYPE 0402LF
J 0
(9600 825);
DISPLAY 0.978723 (9600 825);
PAINT SKYBLUE (9600 825);
DISPLAY INVISIBLE (9600 825);
FORCEADD Q_RES..1
(9450 4500);
FORCEPROP 1 LAST LOCATION R1225
J 0
(9250 4500);
DISPLAY 0.489362 (9250 4500);
PAINT SKYBLUE (9250 4500);
FORCEPROP 2 LAST $SEC 1
J 0
(9400 4700);
DISPLAY 0.680851 (9400 4700);
PAINT MONO (9400 4700);
DISPLAY INVISIBLE (9400 4700);
FORCEPROP 2 LAST CDS_SEC 1
J 0
(9400 4700);
DISPLAY 0.680851 (9400 4700);
DISPLAY INVISIBLE (9400 4700);
FORCEPROP 1 LASTPIN (9350 4500) $PN 1
J 0
(9362 4512);
DISPLAY 0.489362 (9362 4512);
PAINT MONO (9362 4512);
FORCEPROP 1 LASTPIN (9550 4500) $PN 2
J 0
(9512 4512);
DISPLAY 0.489362 (9512 4512);
PAINT MONO (9512 4512);
FORCEPROP 1 LAST MATERIAL EMPTY
J 0
(9600 4500);
DISPLAY 0.489362 (9600 4500);
PAINT RED (9600 4500);
FORCEPROP 1 LAST VALUE 100
J 2
(9575 4500);
DISPLAY 0.489362 (9575 4500);
PAINT SKYBLUE (9575 4500);
FORCEPROP 2 LAST CDS_LIB pure_quanta
J 0
(9450 4500);
DISPLAY INVISIBLE (9450 4500);
FORCEPROP 1 LAST PATH I514
J 0
(9400 4650);
DISPLAY 0.978723 (9400 4650);
PAINT WHITE (9400 4650);
DISPLAY INVISIBLE (9400 4650);
FORCEPROP 1 LAST WATTAGE 1/16W
J 2
(9425 4350);
DISPLAY 0.978723 (9425 4350);
PAINT SKYBLUE (9425 4350);
DISPLAY INVISIBLE (9425 4350);
FORCEPROP 1 LAST TOLERANCE 1%
J 0
(9450 4400);
DISPLAY 0.978723 (9450 4400);
PAINT SKYBLUE (9450 4400);
DISPLAY INVISIBLE (9450 4400);
FORCEPROP 1 LAST PART_NUMBER TMP_QCS11002FB22
J 0
(9400 4600);
DISPLAY 0.978723 (9400 4600);
PAINT SKYBLUE (9400 4600);
DISPLAY INVISIBLE (9400 4600);
FORCEPROP 1 LAST PACK_TYPE 0402LF
J 0
(9700 4350);
DISPLAY 0.978723 (9700 4350);
PAINT SKYBLUE (9700 4350);
DISPLAY INVISIBLE (9700 4350);
FORCEADD Q_RES..1
(9450 4400);
FORCEPROP 1 LAST LOCATION R1226
J 0
(9250 4400);
DISPLAY 0.489362 (9250 4400);
PAINT SKYBLUE (9250 4400);
FORCEPROP 2 LAST $SEC 1
J 0
(9400 4600);
DISPLAY 0.680851 (9400 4600);
PAINT MONO (9400 4600);
DISPLAY INVISIBLE (9400 4600);
FORCEPROP 2 LAST CDS_SEC 1
J 0
(9400 4600);
DISPLAY 0.680851 (9400 4600);
DISPLAY INVISIBLE (9400 4600);
FORCEPROP 1 LASTPIN (9350 4400) $PN 1
J 0
(9362 4412);
DISPLAY 0.489362 (9362 4412);
PAINT MONO (9362 4412);
FORCEPROP 1 LASTPIN (9550 4400) $PN 2
J 0
(9512 4412);
DISPLAY 0.489362 (9512 4412);
PAINT MONO (9512 4412);
FORCEPROP 1 LAST MATERIAL EMPTY
J 0
(9600 4400);
DISPLAY 0.489362 (9600 4400);
PAINT RED (9600 4400);
FORCEPROP 1 LAST VALUE 100
J 2
(9575 4400);
DISPLAY 0.489362 (9575 4400);
PAINT SKYBLUE (9575 4400);
FORCEPROP 2 LAST CDS_LIB pure_quanta
J 0
(9450 4400);
DISPLAY INVISIBLE (9450 4400);
FORCEPROP 1 LAST PATH I515
J 0
(9400 4550);
DISPLAY 0.978723 (9400 4550);
PAINT WHITE (9400 4550);
DISPLAY INVISIBLE (9400 4550);
FORCEPROP 1 LAST WATTAGE 1/16W
J 2
(9425 4250);
DISPLAY 0.978723 (9425 4250);
PAINT SKYBLUE (9425 4250);
DISPLAY INVISIBLE (9425 4250);
FORCEPROP 1 LAST TOLERANCE 1%
J 0
(9450 4300);
DISPLAY 0.978723 (9450 4300);
PAINT SKYBLUE (9450 4300);
DISPLAY INVISIBLE (9450 4300);
FORCEPROP 1 LAST PART_NUMBER TMP_QCS11002FB22
J 0
(9400 4500);
DISPLAY 0.978723 (9400 4500);
PAINT SKYBLUE (9400 4500);
DISPLAY INVISIBLE (9400 4500);
FORCEPROP 1 LAST PACK_TYPE 0402LF
J 0
(9700 4250);
DISPLAY 0.978723 (9700 4250);
PAINT SKYBLUE (9700 4250);
DISPLAY INVISIBLE (9700 4250);
FORCEADD Q_RES..1
(9450 4300);
FORCEPROP 1 LAST LOCATION R1227
J 0
(9250 4300);
DISPLAY 0.489362 (9250 4300);
PAINT SKYBLUE (9250 4300);
FORCEPROP 2 LAST $SEC 1
J 0
(9400 4500);
DISPLAY 0.680851 (9400 4500);
PAINT MONO (9400 4500);
DISPLAY INVISIBLE (9400 4500);
FORCEPROP 2 LAST CDS_SEC 1
J 0
(9400 4500);
DISPLAY 0.680851 (9400 4500);
DISPLAY INVISIBLE (9400 4500);
FORCEPROP 1 LASTPIN (9350 4300) $PN 1
J 0
(9362 4312);
DISPLAY 0.489362 (9362 4312);
PAINT MONO (9362 4312);
FORCEPROP 1 LASTPIN (9550 4300) $PN 2
J 0
(9512 4312);
DISPLAY 0.489362 (9512 4312);
PAINT MONO (9512 4312);
FORCEPROP 1 LAST MATERIAL EMPTY
J 0
(9600 4300);
DISPLAY 0.489362 (9600 4300);
PAINT RED (9600 4300);
FORCEPROP 1 LAST VALUE 100
J 2
(9575 4300);
DISPLAY 0.489362 (9575 4300);
PAINT SKYBLUE (9575 4300);
FORCEPROP 2 LAST CDS_LIB pure_quanta
J 0
(9450 4300);
DISPLAY INVISIBLE (9450 4300);
FORCEPROP 1 LAST PATH I516
J 0
(9400 4450);
DISPLAY 0.978723 (9400 4450);
PAINT WHITE (9400 4450);
DISPLAY INVISIBLE (9400 4450);
FORCEPROP 1 LAST WATTAGE 1/16W
J 2
(9425 4150);
DISPLAY 0.978723 (9425 4150);
PAINT SKYBLUE (9425 4150);
DISPLAY INVISIBLE (9425 4150);
FORCEPROP 1 LAST TOLERANCE 1%
J 0
(9450 4200);
DISPLAY 0.978723 (9450 4200);
PAINT SKYBLUE (9450 4200);
DISPLAY INVISIBLE (9450 4200);
FORCEPROP 1 LAST PART_NUMBER TMP_QCS11002FB22
J 0
(9400 4400);
DISPLAY 0.978723 (9400 4400);
PAINT SKYBLUE (9400 4400);
DISPLAY INVISIBLE (9400 4400);
FORCEPROP 1 LAST PACK_TYPE 0402LF
J 0
(9700 4150);
DISPLAY 0.978723 (9700 4150);
PAINT SKYBLUE (9700 4150);
DISPLAY INVISIBLE (9700 4150);
FORCEADD OFFPAGE..4
(10275 4625);
FORCEPROP 2 LAST $XR0 79 
J 0
(10461 4625);
DISPLAY 0.638298 (10461 4625);
PAINT MONO (10461 4625);
FORCEPROP 2 LAST CDS_LIB standard
J 0
(10275 4625);
DISPLAY INVISIBLE (10275 4625);
FORCEPROP 1 LAST COMMENT_BODY TRUE
J 0
(10250 4525);
DISPLAY 0.872340 (10250 4525);
PAINT GREEN (10250 4525);
DISPLAY INVISIBLE (10250 4525);
FORCEPROP 1 LAST OFFPAGE TRUE
J 0
(10600 4500);
DISPLAY 0.872340 (10600 4500);
PAINT GREEN (10600 4500);
DISPLAY INVISIBLE (10600 4500);
FORCEPROP 2 LAST PATH I517
J 0
(10450 4700);
DISPLAY 0.680851 (10450 4700);
DISPLAY INVISIBLE (10450 4700);
FORCEADD OFFPAGE..4
(10275 4675);
FORCEPROP 2 LAST $XR0 79 
J 0
(10461 4675);
DISPLAY 0.638298 (10461 4675);
PAINT MONO (10461 4675);
FORCEPROP 2 LAST CDS_LIB standard
J 0
(10275 4675);
DISPLAY INVISIBLE (10275 4675);
FORCEPROP 1 LAST COMMENT_BODY TRUE
J 0
(10250 4575);
DISPLAY 0.872340 (10250 4575);
PAINT GREEN (10250 4575);
DISPLAY INVISIBLE (10250 4575);
FORCEPROP 1 LAST OFFPAGE TRUE
J 0
(10600 4550);
DISPLAY 0.872340 (10600 4550);
PAINT GREEN (10600 4550);
DISPLAY INVISIBLE (10600 4550);
FORCEPROP 2 LAST PATH I518
J 0
(10450 4750);
DISPLAY 0.680851 (10450 4750);
DISPLAY INVISIBLE (10450 4750);
FORCEADD OFFPAGE..4
(10275 4725);
FORCEPROP 2 LAST $XR0 79 
J 0
(10461 4725);
DISPLAY 0.638298 (10461 4725);
PAINT MONO (10461 4725);
FORCEPROP 2 LAST PATH I519
J 0
(10475 4775);
DISPLAY 0.680851 (10475 4775);
DISPLAY INVISIBLE (10475 4775);
FORCEPROP 1 LAST OFFPAGE TRUE
J 0
(10600 4600);
DISPLAY 0.872340 (10600 4600);
PAINT GREEN (10600 4600);
DISPLAY INVISIBLE (10600 4600);
FORCEPROP 1 LAST COMMENT_BODY TRUE
J 0
(10250 4625);
DISPLAY 0.872340 (10250 4625);
PAINT GREEN (10250 4625);
DISPLAY INVISIBLE (10250 4625);
FORCEPROP 2 LAST CDS_LIB standard
J 0
(10275 4725);
DISPLAY INVISIBLE (10275 4725);
FORCEADD OFFPAGE..4
(10275 4775);
FORCEPROP 2 LAST $XR0 79 
J 0
(10461 4775);
DISPLAY 0.638298 (10461 4775);
PAINT MONO (10461 4775);
FORCEPROP 2 LAST CDS_LIB standard
J 0
(10275 4775);
DISPLAY INVISIBLE (10275 4775);
FORCEPROP 1 LAST COMMENT_BODY TRUE
J 0
(10250 4675);
DISPLAY 0.872340 (10250 4675);
PAINT GREEN (10250 4675);
DISPLAY INVISIBLE (10250 4675);
FORCEPROP 1 LAST OFFPAGE TRUE
J 0
(10600 4650);
DISPLAY 0.872340 (10600 4650);
PAINT GREEN (10600 4650);
DISPLAY INVISIBLE (10600 4650);
FORCEPROP 2 LAST PATH I523
J 0
(10475 4825);
DISPLAY 0.680851 (10475 4825);
DISPLAY INVISIBLE (10475 4825);
FORCEADD DNS..2
(4775 3325);
PAINT RED (4775 3325);
FORCEPROP 2 LAST CDS_LIB mstr_misc
J 0
(4775 3325);
DISPLAY INVISIBLE (4775 3325);
FORCEPROP 1 LAST COMMENT_BODY TRUE
J 0
(4775 3325);
DISPLAY INVISIBLE (4775 3325);
FORCEADD DNS..2
(4525 3675);
PAINT RED (4525 3675);
FORCEPROP 2 LAST CDS_LIB mstr_misc
J 0
(4525 3675);
DISPLAY INVISIBLE (4525 3675);
FORCEPROP 1 LAST COMMENT_BODY TRUE
J 0
(4525 3675);
DISPLAY INVISIBLE (4525 3675);
FORCEADD DESIGN_NOTE..1
(7575 975);
FORCEPROP 0 LAST L1 ADDRESS : 6D/DA
J 0
(7375 850);
DISPLAY 1.276596 (7375 850);
FORCEPROP 2 LAST CDS_LIB pure_quanta_power
J 0
(7575 975);
DISPLAY INVISIBLE (7575 975);
FORCEPROP 1 LAST COMMENT_BODY TRUE
J 0
(7600 1075);
DISPLAY 0.978723 (7600 1075);
DISPLAY INVISIBLE (7600 1075);
FORCEADD DNS..2
(4800 3700);
PAINT RED (4800 3700);
FORCEPROP 2 LAST CDS_LIB mstr_misc
J 0
(4800 3700);
DISPLAY INVISIBLE (4800 3700);
FORCEPROP 1 LAST COMMENT_BODY TRUE
J 0
(4800 3700);
DISPLAY INVISIBLE (4800 3700);
FORCEADD DNS..2
(9350 950);
PAINT RED (9350 950);
FORCEPROP 2 LAST CDS_LIB mstr_misc
J 0
(9350 950);
DISPLAY INVISIBLE (9350 950);
FORCEPROP 1 LAST COMMENT_BODY TRUE
J 0
(9350 950);
DISPLAY INVISIBLE (9350 950);
FORCEADD DNS..2
(9350 1275);
PAINT RED (9350 1275);
FORCEPROP 2 LAST CDS_LIB mstr_misc
J 0
(9350 1275);
DISPLAY INVISIBLE (9350 1275);
FORCEPROP 1 LAST COMMENT_BODY TRUE
J 0
(9350 1275);
DISPLAY INVISIBLE (9350 1275);
FORCEADD DNS..2
(4525 3300);
PAINT RED (4525 3300);
FORCEPROP 2 LAST CDS_LIB mstr_misc
J 0
(4525 3300);
DISPLAY INVISIBLE (4525 3300);
FORCEPROP 1 LAST COMMENT_BODY TRUE
J 0
(4525 3300);
DISPLAY INVISIBLE (4525 3300);
FORCEADD DNS..2
(2825 3650);
PAINT RED (2825 3650);
FORCEPROP 2 LAST CDS_LIB mstr_misc
J 0
(2825 3650);
DISPLAY INVISIBLE (2825 3650);
FORCEPROP 1 LAST COMMENT_BODY TRUE
J 0
(2825 3650);
DISPLAY INVISIBLE (2825 3650);
FORCEADD DNS..2
(9350 1100);
PAINT RED (9350 1100);
FORCEPROP 2 LAST CDS_LIB mstr_misc
J 0
(9350 1100);
DISPLAY INVISIBLE (9350 1100);
FORCEPROP 1 LAST COMMENT_BODY TRUE
J 0
(9350 1100);
DISPLAY INVISIBLE (9350 1100);
FORCEADD DNS..2
(9350 1175);
PAINT RED (9350 1175);
FORCEPROP 2 LAST CDS_LIB mstr_misc
J 0
(9350 1175);
DISPLAY INVISIBLE (9350 1175);
FORCEPROP 1 LAST COMMENT_BODY TRUE
J 0
(9350 1175);
DISPLAY INVISIBLE (9350 1175);
FORCEADD DESIGN_NOTE..1
(7700 4125);
FORCEPROP 0 LAST L1 ADDRESS : 6C/D8
J 0
(7500 4000);
DISPLAY 1.276596 (7500 4000);
FORCEPROP 2 LAST CDS_LIB pure_quanta_power
J 0
(7700 4125);
DISPLAY INVISIBLE (7700 4125);
FORCEPROP 1 LAST COMMENT_BODY TRUE
J 0
(7725 4225);
DISPLAY 0.978723 (7725 4225);
DISPLAY INVISIBLE (7725 4225);
FORCEADD QUANTA_TITLE_BLOCK_C..1
(11050 100);
FORCEPROP 0 LAST CDS_CON_LAST_MODIFIED Fri Mar 11 14:53:10 2022
J 0
(9165 115);
DISPLAY INVISIBLE (9165 115);
FORCEPROP 1 LAST CUSTOM_TXT_CDS <CON_LAST_MODIFIED>
J 0
(9165 115);
DISPLAY 0.978723 (9165 115);
FORCEPROP 2 LAST CUSTOM_TXT_CDS <XR_PAGE_TITLE>
J 0
(3160 5350);
DISPLAY 0.638298 (3160 5350);
PAINT PINK (3160 5350);
DISPLAY INVISIBLE (3160 5350);
FORCEPROP 1 LAST CUSTOM_TXT_CDS <NAME_2>
J 0
(7875 150);
FORCEPROP 1 LAST CUSTOM_TXT_CDS <NAME_1>
J 0
(7875 275);
FORCEPROP 1 LAST CUSTOM_TXT_CDS <Q_NUMBER>
J 0
(9647 203);
DISPLAY 1.212766 (9647 203);
FORCEPROP 1 LAST CUSTOM_TXT_CDS <Q_PROJ>
J 0
(8668 202);
DISPLAY 1.212766 (8668 202);
FORCEPROP 1 LAST CUSTOM_TXT_CDS <Q_REV>
J 0
(10866 203);
DISPLAY 1.212766 (10866 203);
FORCEPROP 1 LAST CUSTOM_TXT_CDS <CON_PAGE_NUM> OF <CON_TOTAL_PAGES>
J 0
(10604 118);
DISPLAY 0.978723 (10604 118);
FORCEPROP 1 LAST Q_TITLE CLK BUF - PCIEX32 CONN
J 0
(1775 200);
DISPLAY 2.446809 (1775 200);
PAINT GREEN (1775 200);
FORCEPROP 1 LAST Q_DEPT BU9
J 1
(7312 149);
DISPLAY 1.957447 (7312 149);
PAINT GREEN (7312 149);
FORCEPROP 2 LAST CDS_LIB pure_quanta
J 0
(11050 100);
DISPLAY INVISIBLE (11050 100);
FORCEPROP 1 LAST CDS_LMAN_SYM_OUTLINE -9475,6775,100,-125
J 0
(11050 100);
DISPLAY 0.468085 (11050 100);
PAINT GREEN (11050 100);
DISPLAY INVISIBLE (11050 100);
FORCEPROP 2 LAST PAGE_BORDER TRUE
J 0
(3160 5350);
DISPLAY 0.638298 (3160 5350);
PAINT PINK (3160 5350);
DISPLAY INVISIBLE (3160 5350);
FORCEPROP 1 LAST COMMENT_BODY TRUE
J 0
(11062 87);
DISPLAY 0.978723 (11062 87);
PAINT GREEN (11062 87);
DISPLAY INVISIBLE (11062 87);
FORCEPROP 2 LAST CDS_XR_PAGE_TITLE CR-110 : @T6G_MB_LIB.T6G(SCH_1):PAGE110
J 0
(3160 5350);
DISPLAY 0.638298 (3160 5350);
PAINT PINK (3160 5350);
DISPLAY INVISIBLE (3160 5350);
FORCEADD DNS..2
(9500 4250);
PAINT RED (9500 4250);
FORCEPROP 2 LAST CDS_LIB mstr_misc
J 0
(9500 4250);
DISPLAY INVISIBLE (9500 4250);
FORCEPROP 1 LAST COMMENT_BODY TRUE
J 0
(9500 4250);
DISPLAY INVISIBLE (9500 4250);
FORCEADD DNS..2
(9500 4375);
PAINT RED (9500 4375);
FORCEPROP 2 LAST CDS_LIB mstr_misc
J 0
(9500 4375);
DISPLAY INVISIBLE (9500 4375);
FORCEPROP 1 LAST COMMENT_BODY TRUE
J 0
(9500 4375);
DISPLAY INVISIBLE (9500 4375);
FORCEADD DNS..2
(9500 4475);
PAINT RED (9500 4475);
FORCEPROP 2 LAST CDS_LIB mstr_misc
J 0
(9500 4475);
DISPLAY INVISIBLE (9500 4475);
FORCEPROP 1 LAST COMMENT_BODY TRUE
J 0
(9500 4475);
DISPLAY INVISIBLE (9500 4475);
WIRE 16 -1 (2325 4660)(2325 4525);
WIRE 16 -1 (2725 4625)(2725 4500);
WIRE 16 -1 (2975 4625)(2975 4500);
WIRE 16 -1 (3200 4625)(3200 4500);
WIRE 16 -1 (3430 4620)(3430 4495);
WIRE 16 -1 (3660 4615)(3660 4490);
WIRE 16 -1 (4225 5150)(4225 5025);
WIRE 16 -1 (4475 5150)(4475 5025);
WIRE 16 -1 (4675 5150)(4675 5025);
WIRE 16 -1 (2325 1135)(2325 1000);
WIRE 16 -1 (2725 1100)(2725 975);
WIRE 16 -1 (2975 1100)(2975 975);
WIRE 16 -1 (3200 1100)(3200 975);
WIRE 16 -1 (3430 1095)(3430 970);
WIRE 16 -1 (3660 1090)(3660 965);
WIRE 16 -1 (4275 1625)(4275 1500);
WIRE 16 -1 (4525 1625)(4525 1500);
WIRE 16 -1 (4725 1625)(4725 1500);
WIRE 16 -1 (9275 2950)(9275 2900);
WIRE 16 -1 (9200 6100)(9200 6050);
WIRE 16 -1 (8400 4425)(8400 4325);
WIRE 16 -1 (8400 4425)(8325 4425);
WIRE 16 -1 (8425 1250)(8425 1150);
WIRE 16 -1 (8425 1250)(8350 1250);
WIRE 16 -1 (2825 3725)(2825 3825);
WIRE 16 -1 (2825 3100)(2825 3075);
WIRE 16 -1 (3050 3725)(3050 3825);
WIRE 16 -1 (3050 3100)(3050 3075);
WIRE 16 -1 (1800 1975)(1800 1875);
WIRE 16 -1 (1800 1875)(2050 1875);
WIRE 16 -1 (3660 1375)(3660 1290);
WIRE 16 -1 (3430 1375)(3660 1375);
WIRE 16 -1 (3430 1295)(3430 1375);
WIRE 16 -1 (3200 1375)(3430 1375);
WIRE 16 -1 (3200 1375)(3200 1300);
WIRE 16 -1 (2975 1375)(3200 1375);
WIRE 16 -1 (2975 1300)(2975 1375);
WIRE 16 -1 (2725 1375)(2975 1375);
WIRE 16 -1 (2725 1300)(2725 1375);
WIRE 16 -1 (2725 1375)(2325 1375);
WIRE 16 -1 (2325 1875)(2325 1375);
WIRE 16 -1 (2325 1375)(2325 1335);
WIRE 16 -1 (3475 1875)(2325 1875);
WIRE 16 -1 (2325 1875)(2250 1875);
WIRE 16 -1 (3475 1875)(3725 1875);
WIRE 16 -1 (3475 2025)(3475 1875);
WIRE 16 -1 (2825 3300)(2825 3475);
WIRE 16 -1 (3850 3475)(2825 3475);
FORCEPROP 2 LAST SIG_NAME SADR_0
J 0
(3640 3485);
DISPLAY 0.489362 (3640 3485);
WIRE 16 -1 (2825 3475)(2825 3525);
WIRE 16 -1 (3050 3300)(3050 3375);
WIRE 16 -1 (3850 3375)(3050 3375);
FORCEPROP 2 LAST SIG_NAME SADR_1
J 0
(3640 3385);
DISPLAY 0.489362 (3640 3385);
WIRE 16 -1 (3050 3375)(3050 3525);
WIRE 16 -1 (1800 5500)(1800 5400);
WIRE 16 -1 (1800 5400)(2050 5400);
WIRE 16 -1 (3475 5550)(3475 5400);
WIRE 16 -1 (3475 5400)(3725 5400);
WIRE 16 -1 (3475 5400)(2325 5400);
WIRE 16 -1 (2325 5400)(2250 5400);
WIRE 16 -1 (2325 5400)(2325 4900);
WIRE 16 -1 (2725 4900)(2325 4900);
WIRE 16 -1 (2325 4900)(2325 4860);
WIRE 16 -1 (2725 4900)(2975 4900);
WIRE 16 -1 (2725 4825)(2725 4900);
WIRE 16 -1 (2975 4900)(3200 4900);
WIRE 16 -1 (2975 4825)(2975 4900);
WIRE 16 -1 (3200 4900)(3430 4900);
WIRE 16 -1 (3200 4900)(3200 4825);
WIRE 16 -1 (3430 4900)(3660 4900);
WIRE 16 -1 (3430 4820)(3430 4900);
WIRE 16 -1 (3660 4900)(3660 4815);
WIRE 16 -1 (4725 1875)(4725 2025);
WIRE 16 -1 (4725 1825)(4725 1875);
WIRE 16 -1 (4525 1875)(4725 1875);
WIRE 16 -1 (4525 1825)(4525 1875);
WIRE 16 -1 (4275 1875)(4525 1875);
WIRE 16 -1 (3925 1875)(4275 1875);
WIRE 16 -1 (4275 1825)(4275 1875);
WIRE 16 -1 (4800 3125)(4550 3125);
WIRE 16 -1 (4800 3175)(4800 3125);
WIRE 16 -1 (4550 3125)(4550 3075);
WIRE 16 -1 (4550 3175)(4550 3125);
WIRE 16 -1 (4550 3850)(4800 3850);
WIRE 16 -1 (4550 3850)(4550 3875);
WIRE 16 -1 (4550 3775)(4550 3850);
WIRE 16 -1 (4800 3850)(4800 3775);
WIRE 16 -1 (4800 3425)(5700 3425);
FORCEPROP 2 LAST SIG_NAME FM_CLK_BUFFER1_EN
J 0
(5065 3435);
DISPLAY 0.489362 (5065 3435);
WIRE 16 -1 (4800 3575)(4800 3425);
WIRE 16 -1 (4800 3425)(4800 3375);
WIRE 16 -1 (4550 3375)(4550 3500);
WIRE 16 -1 (4550 3500)(5700 3500);
FORCEPROP 2 LAST SIG_NAME FM_CLK_BUFFER0_EN
J 0
(5065 3510);
DISPLAY 0.489362 (5065 3510);
WIRE 16 -1 (4550 3500)(4550 3575);
WIRE 16 -1 (5500 1750)(6150 1750);
FORCEPROP 2 LAST SIG_NAME SMB_CPU0_2_XLTR_SCL
J 0
(5515 1760);
DISPLAY 0.489362 (5515 1760);
WIRE 16 -1 (5500 1800)(6150 1800);
FORCEPROP 2 LAST SIG_NAME SMB_CPU0_2_XLTR_SDA
J 0
(5515 1810);
DISPLAY 0.489362 (5515 1810);
WIRE 16 -1 (5500 1650)(6150 1650);
FORCEPROP 2 LAST SIG_NAME FM_CLK_BUFFER1_EN
J 0
(5515 1660);
DISPLAY 0.489362 (5515 1660);
WIRE 16 -1 (7100 1650)(6350 1650);
FORCEPROP 2 LAST SIG_NAME FM_CLK_BUFFER1_EN_R
J 0
(6440 1660);
DISPLAY 0.489362 (6440 1660);
FORCEPROP 2 LASTPROP $XRERR UNIQUE?
J 0
(6200 1660);
DISPLAY 0.638298 (6200 1660);
PAINT MONO (6200 1660);
DISPLAY INVISIBLE (6200 1660);
WIRE 16 -1 (6350 1750)(7100 1750);
FORCEPROP 2 LAST SIG_NAME SMB_CLK_BUF1_SCL
J 0
(6440 1760);
DISPLAY 0.489362 (6440 1760);
FORCEPROP 2 LASTPROP $XRERR UNIQUE?
J 0
(6200 1760);
DISPLAY 0.638298 (6200 1760);
PAINT MONO (6200 1760);
DISPLAY INVISIBLE (6200 1760);
WIRE 16 -1 (6350 1800)(7100 1800);
FORCEPROP 2 LAST SIG_NAME SMB_CLK_BUF1_SDA
J 0
(6440 1810);
DISPLAY 0.489362 (6440 1810);
FORCEPROP 2 LASTPROP $XRERR UNIQUE?
J 0
(6200 1810);
DISPLAY 0.638298 (6200 1810);
PAINT MONO (6200 1810);
DISPLAY INVISIBLE (6200 1810);
WIRE 16 -1 (6300 2000)(7100 2000);
FORCEPROP 2 LAST SIG_NAME CLK_100M_CPU1_CLK13_DN
J 0
(6465 2010);
DISPLAY 0.489362 (6465 2010);
WIRE 16 -1 (7100 1900)(6300 1900);
FORCEPROP 2 LAST SIG_NAME SADR_1
J 0
(6465 1910);
DISPLAY 0.489362 (6465 1910);
WIRE 16 -1 (6475 2400)(6475 2200);
WIRE 16 -1 (7100 2200)(6475 2200);
WIRE 16 -1 (6300 2050)(7100 2050);
FORCEPROP 2 LAST SIG_NAME CLK_100M_CPU1_CLK13_DP
J 0
(6465 2060);
DISPLAY 0.489362 (6465 2060);
WIRE 16 -1 (6875 2500)(6875 2775);
WIRE 16 -1 (7100 2500)(6875 2500);
WIRE 16 -1 (6875 2450)(6875 2500);
WIRE 16 -1 (7100 2450)(6875 2450);
WIRE 16 -1 (6875 2400)(6875 2450);
WIRE 16 -1 (7100 2400)(6875 2400);
WIRE 16 -1 (6875 2350)(6875 2400);
WIRE 16 -1 (7100 2350)(6875 2350);
WIRE 16 -1 (6875 2300)(6875 2350);
WIRE 16 -1 (7100 2300)(6875 2300);
WIRE 16 -1 (4675 5400)(4675 5550);
WIRE 16 -1 (4675 5350)(4675 5400);
WIRE 16 -1 (4475 5400)(4675 5400);
WIRE 16 -1 (4475 5350)(4475 5400);
WIRE 16 -1 (4225 5400)(4475 5400);
WIRE 16 -1 (3925 5400)(4225 5400);
WIRE 16 -1 (4225 5350)(4225 5400);
WIRE 16 -1 (5475 4925)(6125 4925);
FORCEPROP 2 LAST SIG_NAME SMB_CPU0_2_XLTR_SCL
J 0
(5490 4935);
DISPLAY 0.489362 (5490 4935);
WIRE 16 -1 (5475 4975)(6125 4975);
FORCEPROP 2 LAST SIG_NAME SMB_CPU0_2_XLTR_SDA
J 0
(5490 4985);
DISPLAY 0.489362 (5490 4985);
WIRE 16 -1 (5475 4825)(6125 4825);
FORCEPROP 2 LAST SIG_NAME FM_CLK_BUFFER0_EN
J 0
(5490 4835);
DISPLAY 0.489362 (5490 4835);
WIRE 16 -1 (7075 4925)(6325 4925);
FORCEPROP 2 LAST SIG_NAME SMB_CLK_BUF0_SCL
J 0
(6415 4935);
DISPLAY 0.489362 (6415 4935);
FORCEPROP 2 LASTPROP $XRERR UNIQUE?
J 0
(6175 4935);
DISPLAY 0.638298 (6175 4935);
PAINT MONO (6175 4935);
DISPLAY INVISIBLE (6175 4935);
WIRE 16 -1 (7075 4975)(6325 4975);
FORCEPROP 2 LAST SIG_NAME SMB_CLK_BUF0_SDA
J 0
(6415 4985);
DISPLAY 0.489362 (6415 4985);
FORCEPROP 2 LASTPROP $XRERR UNIQUE?
J 0
(6175 4985);
DISPLAY 0.638298 (6175 4985);
PAINT MONO (6175 4985);
DISPLAY INVISIBLE (6175 4985);
WIRE 16 -1 (7075 4825)(6325 4825);
FORCEPROP 2 LAST SIG_NAME FM_CLK_BUFFER0_EN_R
J 0
(6415 4835);
DISPLAY 0.489362 (6415 4835);
FORCEPROP 2 LASTPROP $XRERR UNIQUE?
J 0
(6175 4835);
DISPLAY 0.638298 (6175 4835);
PAINT MONO (6175 4835);
DISPLAY INVISIBLE (6175 4835);
WIRE 16 -1 (7075 5075)(6275 5075);
FORCEPROP 2 LAST SIG_NAME SADR_0
J 0
(6440 5085);
DISPLAY 0.489362 (6440 5085);
WIRE 16 -1 (6450 5575)(6450 5375);
WIRE 16 -1 (7075 5375)(6450 5375);
WIRE 16 -1 (6275 5175)(7075 5175);
FORCEPROP 2 LAST SIG_NAME CLK_100M_CPU0_CLK13_DN
J 0
(6440 5185);
DISPLAY 0.489362 (6440 5185);
WIRE 16 -1 (6275 5225)(7075 5225);
FORCEPROP 2 LAST SIG_NAME CLK_100M_CPU0_CLK13_DP
J 0
(6440 5235);
DISPLAY 0.489362 (6440 5235);
WIRE 16 -1 (7075 5675)(6850 5675);
WIRE 16 -1 (6850 5675)(6850 5950);
WIRE 16 -1 (6850 5625)(6850 5675);
WIRE 16 -1 (7075 5625)(6850 5625);
WIRE 16 -1 (6850 5575)(6850 5625);
WIRE 16 -1 (7075 5575)(6850 5575);
WIRE 16 -1 (6850 5525)(6850 5575);
WIRE 16 -1 (7075 5525)(6850 5525);
WIRE 16 -1 (6850 5475)(6850 5525);
WIRE 16 -1 (7075 5475)(6850 5475);
WIRE 16 -1 (8350 2000)(9200 2000);
FORCEPROP 2 LAST SIG_NAME CLK_100M_SLOT2_1_R_DN
J 0
(8440 2010);
DISPLAY 0.489362 (8440 2010);
FORCEPROP 2 LASTPROP $XRERR UNIQUE?
J 0
(8200 2010);
DISPLAY 0.638298 (8200 2010);
PAINT MONO (8200 2010);
DISPLAY INVISIBLE (8200 2010);
WIRE 16 -1 (8350 1900)(9200 1900);
FORCEPROP 2 LAST SIG_NAME CLK_100M_SLOT2_2_R_DN
J 0
(8440 1910);
DISPLAY 0.489362 (8440 1910);
FORCEPROP 2 LASTPROP $XRERR UNIQUE?
J 0
(8200 1910);
DISPLAY 0.638298 (8200 1910);
PAINT MONO (8200 1910);
DISPLAY INVISIBLE (8200 1910);
WIRE 16 -1 (8350 1950)(9200 1950);
FORCEPROP 2 LAST SIG_NAME CLK_100M_SLOT2_2_R_DP
J 0
(8440 1960);
DISPLAY 0.489362 (8440 1960);
FORCEPROP 2 LASTPROP $XRERR UNIQUE?
J 0
(8200 1960);
DISPLAY 0.638298 (8200 1960);
PAINT MONO (8200 1960);
DISPLAY INVISIBLE (8200 1960);
WIRE 16 -1 (8350 1850)(9200 1850);
FORCEPROP 2 LAST SIG_NAME CLK_100M_SLOT2_3_R_DP
J 0
(8440 1860);
DISPLAY 0.489362 (8440 1860);
FORCEPROP 2 LASTPROP $XRERR UNIQUE?
J 0
(8200 1860);
DISPLAY 0.638298 (8200 1860);
PAINT MONO (8200 1860);
DISPLAY INVISIBLE (8200 1860);
WIRE 16 -1 (8350 1800)(9200 1800);
FORCEPROP 2 LAST SIG_NAME CLK_100M_SLOT2_3_R_DN
J 0
(8440 1810);
DISPLAY 0.489362 (8440 1810);
FORCEPROP 2 LASTPROP $XRERR UNIQUE?
J 0
(8200 1810);
DISPLAY 0.638298 (8200 1810);
PAINT MONO (8200 1810);
DISPLAY INVISIBLE (8200 1810);
WIRE 16 -1 (9100 1075)(9250 1075);
WIRE 16 -1 (9100 1075)(9100 1500);
WIRE 16 -1 (10250 1500)(9100 1500);
FORCEPROP 2 LAST SIG_NAME FM_CLK_100M_SLOT2_2_OE_N
J 0
(9540 1510);
DISPLAY 0.489362 (9540 1510);
WIRE 16 -1 (8350 1500)(9100 1500);
WIRE 16 -1 (9050 975)(9250 975);
WIRE 16 -1 (9050 1450)(9050 975);
WIRE 16 -1 (10250 1450)(9050 1450);
FORCEPROP 2 LAST SIG_NAME FM_CLK_100M_SLOT2_3_OE_N
J 0
(9540 1460);
DISPLAY 0.489362 (9540 1460);
WIRE 16 -1 (8350 1450)(9050 1450);
WIRE 16 -1 (9150 1150)(9250 1150);
WIRE 16 -1 (9150 1550)(9150 1150);
WIRE 16 -1 (10250 1550)(9150 1550);
FORCEPROP 2 LAST SIG_NAME FM_CLK_100M_SLOT2_1_OE_N
J 0
(9540 1560);
DISPLAY 0.489362 (9540 1560);
WIRE 16 -1 (8350 1550)(9150 1550);
WIRE 16 -1 (9200 1250)(9250 1250);
WIRE 16 -1 (9200 1600)(9200 1250);
WIRE 16 -1 (10250 1600)(9200 1600);
FORCEPROP 2 LAST SIG_NAME FM_CLK_100M_SLOT2_0_OE_N
J 0
(9540 1610);
DISPLAY 0.489362 (9540 1610);
WIRE 16 -1 (9200 1600)(8350 1600);
WIRE 16 -1 (9575 975)(9575 1075);
WIRE 16 -1 (9575 975)(9575 925);
WIRE 16 -1 (9450 975)(9575 975);
WIRE 16 -1 (9575 1075)(9575 1150);
WIRE 16 -1 (9575 1075)(9450 1075);
WIRE 16 -1 (9575 1250)(9575 1150);
WIRE 16 -1 (9575 1150)(9450 1150);
WIRE 16 -1 (9450 1250)(9575 1250);
WIRE 16 -1 (9400 2000)(10125 2000);
FORCEPROP 2 LAST SIG_NAME CLK_100M_SLOT2_1_DN
J 0
(9565 2010);
DISPLAY 0.489362 (9565 2010);
WIRE 16 -1 (9400 1800)(10125 1800);
FORCEPROP 2 LAST SIG_NAME CLK_100M_SLOT2_3_DN
J 0
(9565 1810);
DISPLAY 0.489362 (9565 1810);
WIRE 16 -1 (9400 1950)(10125 1950);
FORCEPROP 2 LAST SIG_NAME CLK_100M_SLOT2_2_DP
J 0
(9565 1960);
DISPLAY 0.489362 (9565 1960);
WIRE 16 -1 (9400 1900)(10125 1900);
FORCEPROP 2 LAST SIG_NAME CLK_100M_SLOT2_2_DN
J 0
(9565 1910);
DISPLAY 0.489362 (9565 1910);
WIRE 16 -1 (9400 1850)(10125 1850);
FORCEPROP 2 LAST SIG_NAME CLK_100M_SLOT2_3_DP
J 0
(9565 1860);
DISPLAY 0.489362 (9565 1860);
WIRE 16 -1 (8350 2350)(8650 2350);
WIRE 16 -1 (8650 2625)(8650 2350);
FORCEPROP 2 LAST SIG_NAME CLKBUF1_PLL_MODE
J 0
(8640 2635);
DISPLAY 0.489362 (8640 2635);
FORCEPROP 2 LASTPROP $XRERR UNIQUE?
J 0
(8400 2635);
DISPLAY 0.638298 (8400 2635);
PAINT MONO (8400 2635);
DISPLAY INVISIBLE (8400 2635);
WIRE 16 -1 (8650 2625)(9275 2625);
WIRE 16 -1 (9275 2700)(9275 2625);
WIRE 16 -1 (9275 2625)(9275 2550);
WIRE 16 -1 (8475 2775)(8475 2500);
WIRE 16 -1 (8350 2500)(8475 2500);
WIRE 16 -1 (8350 2100)(9200 2100);
FORCEPROP 2 LAST SIG_NAME CLK_100M_SLOT2_0_R_DN
J 0
(8440 2110);
DISPLAY 0.489362 (8440 2110);
FORCEPROP 2 LASTPROP $XRERR UNIQUE?
J 0
(8200 2110);
DISPLAY 0.638298 (8200 2110);
PAINT MONO (8200 2110);
DISPLAY INVISIBLE (8200 2110);
WIRE 16 -1 (8350 2150)(9200 2150);
FORCEPROP 2 LAST SIG_NAME CLK_100M_SLOT2_0_R_DP
J 0
(8440 2160);
DISPLAY 0.489362 (8440 2160);
FORCEPROP 2 LASTPROP $XRERR UNIQUE?
J 0
(8200 2160);
DISPLAY 0.638298 (8200 2160);
PAINT MONO (8200 2160);
DISPLAY INVISIBLE (8200 2160);
WIRE 16 -1 (8350 2050)(9200 2050);
FORCEPROP 2 LAST SIG_NAME CLK_100M_SLOT2_1_R_DP
J 0
(8440 2060);
DISPLAY 0.489362 (8440 2060);
FORCEPROP 2 LASTPROP $XRERR UNIQUE?
J 0
(8200 2060);
DISPLAY 0.638298 (8200 2060);
PAINT MONO (8200 2060);
DISPLAY INVISIBLE (8200 2060);
WIRE 16 -1 (9400 2150)(10125 2150);
FORCEPROP 2 LAST SIG_NAME CLK_100M_SLOT2_0_DP
J 0
(9565 2160);
DISPLAY 0.489362 (9565 2160);
WIRE 16 -1 (9400 2100)(10125 2100);
FORCEPROP 2 LAST SIG_NAME CLK_100M_SLOT2_0_DN
J 0
(9565 2110);
DISPLAY 0.489362 (9565 2110);
WIRE 16 -1 (9400 2050)(10125 2050);
FORCEPROP 2 LAST SIG_NAME CLK_100M_SLOT2_1_DP
J 0
(9565 2060);
DISPLAY 0.489362 (9565 2060);
WIRE 16 -1 (8325 5525)(8625 5525);
WIRE 16 -1 (8625 5775)(8625 5525);
WIRE 16 -1 (8625 5775)(9200 5775);
FORCEPROP 2 LAST SIG_NAME CLKBUF0_PLL_MODE
J 0
(8640 5785);
DISPLAY 0.489362 (8640 5785);
FORCEPROP 2 LASTPROP $XRERR UNIQUE?
J 0
(8400 5785);
DISPLAY 0.638298 (8400 5785);
PAINT MONO (8400 5785);
DISPLAY INVISIBLE (8400 5785);
WIRE 16 -1 (9200 5775)(9200 5700);
WIRE 16 -1 (9200 5850)(9200 5775);
WIRE 16 -1 (8450 5950)(8450 5675);
WIRE 16 -1 (8325 5675)(8450 5675);
WIRE 16 -1 (8325 5325)(9350 5325);
FORCEPROP 2 LAST SIG_NAME CLK_100M_SLOT1_0_R_DP
J 0
(8415 5335);
DISPLAY 0.489362 (8415 5335);
FORCEPROP 2 LASTPROP $XRERR UNIQUE?
J 0
(8175 5335);
DISPLAY 0.638298 (8175 5335);
PAINT MONO (8175 5335);
DISPLAY INVISIBLE (8175 5335);
WIRE 16 -1 (8325 5275)(9350 5275);
FORCEPROP 2 LAST SIG_NAME CLK_100M_SLOT1_0_R_DN
J 0
(8415 5285);
DISPLAY 0.489362 (8415 5285);
FORCEPROP 2 LASTPROP $XRERR UNIQUE?
J 0
(8175 5285);
DISPLAY 0.638298 (8175 5285);
PAINT MONO (8175 5285);
DISPLAY INVISIBLE (8175 5285);
WIRE 16 -1 (8325 5225)(9350 5225);
FORCEPROP 2 LAST SIG_NAME CLK_100M_SLOT1_1_R_DP
J 0
(8415 5235);
DISPLAY 0.489362 (8415 5235);
FORCEPROP 2 LASTPROP $XRERR UNIQUE?
J 0
(8175 5235);
DISPLAY 0.638298 (8175 5235);
PAINT MONO (8175 5235);
DISPLAY INVISIBLE (8175 5235);
WIRE 16 -1 (8325 5175)(9350 5175);
FORCEPROP 2 LAST SIG_NAME CLK_100M_SLOT1_1_R_DN
J 0
(8415 5185);
DISPLAY 0.489362 (8415 5185);
FORCEPROP 2 LASTPROP $XRERR UNIQUE?
J 0
(8175 5185);
DISPLAY 0.638298 (8175 5185);
PAINT MONO (8175 5185);
DISPLAY INVISIBLE (8175 5185);
WIRE 16 -1 (8325 5125)(9350 5125);
FORCEPROP 2 LAST SIG_NAME CLK_100M_SLOT1_2_R_DP
J 0
(8415 5135);
DISPLAY 0.489362 (8415 5135);
FORCEPROP 2 LASTPROP $XRERR UNIQUE?
J 0
(8175 5135);
DISPLAY 0.638298 (8175 5135);
PAINT MONO (8175 5135);
DISPLAY INVISIBLE (8175 5135);
WIRE 16 -1 (8325 4975)(9350 4975);
FORCEPROP 2 LAST SIG_NAME CLK_100M_SLOT1_3_R_DN
J 0
(8415 4985);
DISPLAY 0.489362 (8415 4985);
FORCEPROP 2 LASTPROP $XRERR UNIQUE?
J 0
(8175 4985);
DISPLAY 0.638298 (8175 4985);
PAINT MONO (8175 4985);
DISPLAY INVISIBLE (8175 4985);
WIRE 16 -1 (8325 5025)(9350 5025);
FORCEPROP 2 LAST SIG_NAME CLK_100M_SLOT1_3_R_DP
J 0
(8415 5035);
DISPLAY 0.489362 (8415 5035);
FORCEPROP 2 LASTPROP $XRERR UNIQUE?
J 0
(8175 5035);
DISPLAY 0.638298 (8175 5035);
PAINT MONO (8175 5035);
DISPLAY INVISIBLE (8175 5035);
WIRE 16 -1 (8325 5075)(9350 5075);
FORCEPROP 2 LAST SIG_NAME CLK_100M_SLOT1_2_R_DN
J 0
(8415 5085);
DISPLAY 0.489362 (8415 5085);
FORCEPROP 2 LASTPROP $XRERR UNIQUE?
J 0
(8175 5085);
DISPLAY 0.638298 (8175 5085);
PAINT MONO (8175 5085);
DISPLAY INVISIBLE (8175 5085);
WIRE 16 -1 (9150 4500)(9350 4500);
WIRE 16 -1 (9150 4725)(9150 4500);
WIRE 16 -1 (10225 4725)(9150 4725);
FORCEPROP 2 LAST SIG_NAME FM_CLK_100M_SLOT1_1_OE_N
J 0
(9640 4735);
DISPLAY 0.489362 (9640 4735);
WIRE 16 -1 (9150 4725)(8325 4725);
WIRE 16 -1 (9100 4400)(9350 4400);
WIRE 16 -1 (9100 4675)(9100 4400);
WIRE 16 -1 (10225 4675)(9100 4675);
FORCEPROP 2 LAST SIG_NAME FM_CLK_100M_SLOT1_2_OE_N
J 0
(9640 4685);
DISPLAY 0.489362 (9640 4685);
WIRE 16 -1 (8325 4675)(9100 4675);
WIRE 16 -1 (9050 4300)(9350 4300);
WIRE 16 -1 (9050 4625)(9050 4300);
WIRE 16 -1 (10225 4625)(9050 4625);
FORCEPROP 2 LAST SIG_NAME FM_CLK_100M_SLOT1_3_OE_N
J 0
(9640 4635);
DISPLAY 0.489362 (9640 4635);
WIRE 16 -1 (8325 4625)(9050 4625);
WIRE 16 -1 (10225 4775)(8325 4775);
FORCEPROP 2 LAST SIG_NAME FM_CLK_100M_SLOT1_0_OE_N
J 0
(9640 4785);
DISPLAY 0.489362 (9640 4785);
WIRE 16 -1 (9675 4400)(9675 4300);
WIRE 16 -1 (9675 4500)(9675 4400);
WIRE 16 -1 (9675 4400)(9550 4400);
WIRE 16 -1 (9675 4300)(9550 4300);
WIRE 16 -1 (9675 4300)(9675 4075);
WIRE 16 -1 (9550 4500)(9675 4500);
WIRE 16 -1 (9550 5075)(10225 5075);
FORCEPROP 2 LAST SIG_NAME CLK_100M_SLOT1_2_DN
J 0
(9715 5085);
DISPLAY 0.489362 (9715 5085);
WIRE 16 -1 (9550 4975)(10225 4975);
FORCEPROP 2 LAST SIG_NAME CLK_100M_SLOT1_3_DN
J 0
(9715 4985);
DISPLAY 0.489362 (9715 4985);
WIRE 16 -1 (9550 5025)(10225 5025);
FORCEPROP 2 LAST SIG_NAME CLK_100M_SLOT1_3_DP
J 0
(9715 5035);
DISPLAY 0.489362 (9715 5035);
WIRE 16 -1 (9550 5325)(10225 5325);
FORCEPROP 2 LAST SIG_NAME CLK_100M_SLOT1_0_DP
J 0
(9715 5335);
DISPLAY 0.489362 (9715 5335);
WIRE 16 -1 (9550 5275)(10225 5275);
FORCEPROP 2 LAST SIG_NAME CLK_100M_SLOT1_0_DN
J 0
(9715 5285);
DISPLAY 0.489362 (9715 5285);
WIRE 16 -1 (9550 5175)(10225 5175);
FORCEPROP 2 LAST SIG_NAME CLK_100M_SLOT1_1_DN
J 0
(9715 5185);
DISPLAY 0.489362 (9715 5185);
WIRE 16 -1 (9550 5225)(10225 5225);
FORCEPROP 2 LAST SIG_NAME CLK_100M_SLOT1_1_DP
J 0
(9715 5235);
DISPLAY 0.489362 (9715 5235);
WIRE 16 -1 (9550 5125)(10225 5125);
FORCEPROP 2 LAST SIG_NAME CLK_100M_SLOT1_2_DP
J 0
(9715 5135);
DISPLAY 0.489362 (9715 5135);
DOT 1 (9200 1600);
DOT 1 (9675 4300);
DOT 1 (9100 4675);
DOT 1 (9150 4725);
DOT 1 (2325 1875);
DOT 1 (9675 4400);
DOT 1 (6850 5575);
DOT 1 (6850 5625);
DOT 1 (6850 5675);
DOT 1 (4550 3500);
DOT 1 (2825 3475);
DOT 1 (4550 3125);
DOT 1 (4550 3850);
DOT 1 (2325 1375);
DOT 1 (2725 1375);
DOT 1 (2975 1375);
DOT 1 (3200 1375);
DOT 1 (3430 1375);
DOT 1 (3475 1875);
DOT 1 (4275 1875);
DOT 1 (4525 1875);
DOT 1 (2325 4900);
DOT 1 (2725 4900);
DOT 1 (2975 4900);
DOT 1 (3200 4900);
DOT 1 (3430 4900);
DOT 1 (4225 5400);
DOT 1 (4475 5400);
DOT 1 (4675 5400);
DOT 1 (3050 3375);
DOT 1 (6875 2400);
DOT 1 (6875 2350);
DOT 1 (6875 2500);
DOT 1 (6875 2450);
DOT 1 (9100 1500);
DOT 1 (9050 1450);
DOT 1 (9150 1550);
DOT 1 (4800 3425);
DOT 1 (9575 975);
DOT 1 (9575 1150);
DOT 1 (9575 1075);
DOT 1 (9050 4625);
DOT 1 (2325 5400);
DOT 1 (6850 5525);
DOT 1 (3475 5400);
DOT 1 (4725 1875);
DOT 1 (9200 5775);
DOT 1 (9275 2625);
FORCENOTE
TO SLOT#2
(9850 1025) 0;
DISPLAY LEFT (9850 1025);
DISPLAY 1.595745 (9850 1025);
FORCENOTE
TO SLOT#1
(10050 4025) 0;
DISPLAY LEFT (10050 4025);
DISPLAY 1.595745 (10050 4025);
QUIT
